FILE_TYPE = MACRO_DRAWING;
SET COLOR_WIRE YELLOW;
SET COLOR_PROP ORANGE;
SET COLOR_DOT WHITE;
SET COLOR_ARC YELLOW;
SET COLOR_BODY GREEN;
SET COLOR_NOTE PURPLE;
SET PROP_DISPLAY VALUE;
SET PAGE_NUMBER P248;
FORCEADD UNIVERSAL_GND..1
(-3150 -1700);
FORCEPROP 3 LASTPIN (-3150 -1650) SIG_NAME GND\g
J 0
(-3140 -1640);
DISPLAY 0.659574 (-3140 -1640);
PAINT MONO (-3140 -1640);
DISPLAY INVISIBLE (-3140 -1640);
FORCEPROP 1 LAST HDL_POWER GND
J 1
(-3125 -1775);
DISPLAY 0.872340 (-3125 -1775);
PAINT GREEN (-3125 -1775);
DISPLAY INVISIBLE (-3125 -1775);
FORCEPROP 2 LAST CDS_LIB logical_power
J 0
(-3150 -1700);
DISPLAY INVISIBLE (-3150 -1700);
FORCEPROP 1 LAST PATH I1
J 0
(-3075 -1700);
DISPLAY 0.872340 (-3075 -1700);
PAINT AQUA (-3075 -1700);
DISPLAY INVISIBLE (-3075 -1700);
FORCEADD Q_RES..1
(-1625 -650);
FORCEPROP 1 LAST PART_NUMBER CS00002JB13
J 0
(-1750 -700);
DISPLAY 0.404255 (-1750 -700);
DISPLAY INVISIBLE (-1750 -700);
FORCEPROP 1 LAST PACK_TYPE 0402LF
J 0
(-1650 -725);
DISPLAY 0.404255 (-1650 -725);
FORCEPROP 1 LAST VALUE 0
J 2
(-1475 -650);
DISPLAY 0.404255 (-1475 -650);
FORCEPROP 1 LAST TOLERANCE 5%
J 0
(-1425 -650);
DISPLAY 0.404255 (-1425 -650);
FORCEPROP 1 LAST MATERIAL CHIP
J 0
(-1750 -725);
DISPLAY 0.404255 (-1750 -725);
FORCEPROP 1 LAST WATTAGE 1/16W
J 2
(-1425 -725);
DISPLAY 0.404255 (-1425 -725);
FORCEPROP 1 LAST LOCATION PR338
J 0
(-1875 -650);
DISPLAY 0.404255 (-1875 -650);
FORCEPROP 1 LASTPIN (-1725 -650) $PN 1
J 0
(-1713 -638);
DISPLAY 0.787234 (-1713 -638);
PAINT MONO (-1713 -638);
FORCEPROP 1 LASTPIN (-1525 -650) $PN 2
J 0
(-1563 -638);
DISPLAY 0.787234 (-1563 -638);
PAINT MONO (-1563 -638);
FORCEPROP 2 LAST CDS_LIB pure_quanta
J 0
(-1625 -650);
DISPLAY INVISIBLE (-1625 -650);
FORCEPROP 1 LAST PATH I10
J 0
(-1675 -500);
DISPLAY 0.978723 (-1675 -500);
PAINT WHITE (-1675 -500);
DISPLAY INVISIBLE (-1675 -500);
FORCEPROP 0 LAST $SEC 1
J 0
(-1500 -575);
DISPLAY 0.680851 (-1500 -575);
PAINT MONO (-1500 -575);
DISPLAY INVISIBLE (-1500 -575);
FORCEPROP 0 LAST CDS_SEC 1
J 0
(-1500 -575);
DISPLAY 1.021277 (-1500 -575);
DISPLAY INVISIBLE (-1500 -575);
FORCEADD RS53319LR..1
(-925 -525);
FORCEPROP 1 LAST PART_NUMBER AL053319002
J 0
(-1170 359);
DISPLAY 0.723404 (-1170 359);
PAINT GREEN (-1170 359);
DISPLAY INVISIBLE (-1170 359);
FORCEPROP 2 LAST PART_TYPE SMLF
J 0
(-1175 475);
DISPLAY 1.021277 (-1175 475);
FORCEPROP 2 LAST VALUE RS53319LR
J 0
(-1175 425);
DISPLAY 0.617021 (-1175 425);
PAINT SKYBLUE (-1175 425);
FORCEPROP 1 LAST MATERIAL IC
J 0
(-1170 232);
DISPLAY 0.723404 (-1170 232);
PAINT GREEN (-1170 232);
FORCEPROP 1 LAST LOCATION PU73
J 0
(-1175 550);
DISPLAY 0.914894 (-1175 550);
PAINT GREEN (-1175 550);
FORCEPROP 2 LASTPIN (-525 -1200) $PN 2
J 0
(-515 -1190);
DISPLAY 0.680851 (-515 -1190);
PAINT MONO (-515 -1190);
FORCEPROP 2 LASTPIN (-525 -50) $PN 1
J 0
(-515 -40);
DISPLAY 0.680851 (-515 -40);
PAINT MONO (-515 -40);
FORCEPROP 2 LASTPIN (-1325 -1150) $PN 3
J 2
(-1335 -1140);
DISPLAY 0.680851 (-1335 -1140);
PAINT MONO (-1335 -1140);
FORCEPROP 2 LASTPIN (-1325 -350) $PN 8
J 2
(-1335 -340);
DISPLAY 0.680851 (-1335 -340);
PAINT MONO (-1335 -340);
FORCEPROP 2 LASTPIN (-525 -800) $PN 7
J 0
(-515 -790);
DISPLAY 0.680851 (-515 -790);
PAINT MONO (-515 -790);
FORCEPROP 2 LASTPIN (-1325 -550) $PN 4
J 2
(-1335 -540);
DISPLAY 0.680851 (-1335 -540);
PAINT MONO (-1335 -540);
FORCEPROP 2 LASTPIN (-525 -1150) $PN 11_18
J 0
(-515 -1140);
DISPLAY 0.680851 (-515 -1140);
PAINT MONO (-515 -1140);
FORCEPROP 2 LASTPIN (-525 150) $PN 9
J 0
(-515 160);
DISPLAY 0.680851 (-515 160);
PAINT MONO (-515 160);
FORCEPROP 2 LASTPIN (-525 -1050) $PN 5
J 0
(-515 -1040);
DISPLAY 0.680851 (-515 -1040);
PAINT MONO (-515 -1040);
FORCEPROP 2 LASTPIN (-525 -950) $PN 6
J 0
(-515 -940);
DISPLAY 0.680851 (-515 -940);
PAINT MONO (-515 -940);
FORCEPROP 2 LASTPIN (-525 -350) $PN 20
J 0
(-515 -340);
DISPLAY 0.680851 (-515 -340);
PAINT MONO (-515 -340);
FORCEPROP 2 LASTPIN (-1325 -800) $PN 19
J 2
(-1335 -790);
DISPLAY 0.680851 (-1335 -790);
PAINT MONO (-1335 -790);
FORCEPROP 2 LASTPIN (-1325 150) $PN 10
J 2
(-1335 160);
DISPLAY 0.680851 (-1335 160);
PAINT MONO (-1335 160);
FORCEPROP 2 LASTPIN (-1325 100) $PN 21
J 2
(-1335 110);
DISPLAY 0.680851 (-1335 110);
PAINT MONO (-1335 110);
FORCEPROP 2 LAST SEC_TYPE 
J 0
(-1150 650);
DISPLAY 1.021277 (-1150 650);
DISPLAY INVISIBLE (-1150 650);
FORCEPROP 2 LAST CDS_LIB pure_quanta
J 0
(-925 -525);
DISPLAY INVISIBLE (-925 -525);
FORCEPROP 1 LAST NEEDS_NO_SIZE TRUE
J 0
(-925 -525);
DISPLAY 0.723404 (-925 -525);
PAINT GREEN (-925 -525);
DISPLAY INVISIBLE (-925 -525);
FORCEPROP 1 LAST CDS_LMAN_SYM_OUTLINE -250,725,250,-725
J 0
(-925 -525);
DISPLAY 0.468085 (-925 -525);
PAINT GREEN (-925 -525);
DISPLAY INVISIBLE (-925 -525);
FORCEPROP 1 LAST PATH I11
J 0
(-925 -525);
DISPLAY 0.723404 (-925 -525);
PAINT GREEN (-925 -525);
DISPLAY INVISIBLE (-925 -525);
FORCEPROP 2 LAST SEC 1
J 0
(-1150 650);
DISPLAY 0.680851 (-1150 650);
PAINT MONO (-1150 650);
DISPLAY INVISIBLE (-1150 650);
FORCEADD UNIVERSAL_GND..1
(-1375 -725);
FORCEPROP 3 LASTPIN (-1375 -675) SIG_NAME GND\g
J 0
(-1365 -665);
DISPLAY 0.659574 (-1365 -665);
PAINT MONO (-1365 -665);
DISPLAY INVISIBLE (-1365 -665);
FORCEPROP 1 LAST HDL_POWER GND
J 1
(-1350 -800);
DISPLAY 0.872340 (-1350 -800);
PAINT GREEN (-1350 -800);
DISPLAY INVISIBLE (-1350 -800);
FORCEPROP 2 LAST CDS_LIB logical_power
J 0
(-1375 -725);
DISPLAY INVISIBLE (-1375 -725);
FORCEPROP 1 LAST PATH I12
J 0
(-1300 -725);
DISPLAY 0.872340 (-1300 -725);
PAINT AQUA (-1300 -725);
DISPLAY INVISIBLE (-1300 -725);
FORCEADD UNIVERSAL_GND..1
(-425 -1500);
FORCEPROP 3 LASTPIN (-425 -1450) SIG_NAME GND\g
J 0
(-415 -1440);
DISPLAY 0.659574 (-415 -1440);
PAINT MONO (-415 -1440);
DISPLAY INVISIBLE (-415 -1440);
FORCEPROP 1 LAST HDL_POWER GND
J 1
(-400 -1575);
DISPLAY 0.872340 (-400 -1575);
PAINT GREEN (-400 -1575);
DISPLAY INVISIBLE (-400 -1575);
FORCEPROP 2 LAST CDS_LIB logical_power
J 0
(-425 -1500);
DISPLAY INVISIBLE (-425 -1500);
FORCEPROP 1 LAST PATH I13
J 0
(-350 -1500);
DISPLAY 0.872340 (-350 -1500);
PAINT AQUA (-350 -1500);
DISPLAY INVISIBLE (-350 -1500);
FORCEADD Q_CAP..1
(-275 -1275);
FORCEPROP 1 LAST PART_NUMBER TMP_QCH32203KB11
J 0
(-225 -1425);
DISPLAY 0.510638 (-225 -1425);
DISPLAY INVISIBLE (-225 -1425);
FORCEPROP 1 LAST MATERIAL X7R
J 0
(-225 -1375);
DISPLAY 0.638298 (-225 -1375);
FORCEPROP 1 LAST VOLTAGE 16V
J 0
(-225 -1275);
DISPLAY 0.638298 (-225 -1275);
FORCEPROP 1 LAST PACK_TYPE 0402
J 0
(-225 -1475);
DISPLAY 0.638298 (-225 -1475);
FORCEPROP 1 LAST TOLERANCE 10%
J 0
(-225 -1325);
DISPLAY 0.638298 (-225 -1325);
FORCEPROP 1 LAST VALUE 0.022UF
J 0
(-225 -1225);
DISPLAY 0.638298 (-225 -1225);
FORCEPROP 1 LAST LOCATION PC2000
J 0
(-225 -1175);
DISPLAY 0.638298 (-225 -1175);
FORCEPROP 2 LAST CDS_LIB pure_quanta
J 0
(-275 -1275);
DISPLAY INVISIBLE (-275 -1275);
FORCEPROP 1 LAST PATH I14
J 0
(-225 -1125);
DISPLAY 0.978723 (-225 -1125);
PAINT WHITE (-225 -1125);
DISPLAY INVISIBLE (-225 -1125);
FORCEPROP 0 LAST $SEC 1
J 0
(-225 -1125);
DISPLAY INVISIBLE (-225 -1125);
FORCEPROP 0 LAST CDS_SEC 1
J 0
(-225 -1125);
DISPLAY INVISIBLE (-225 -1125);
FORCEPROP 1 LASTPIN (-275 -1175) $PN 1
J 0
(-265 -1195);
DISPLAY 0.787234 (-265 -1195);
PAINT MONO (-265 -1195);
DISPLAY INVISIBLE (-265 -1195);
FORCEPROP 1 LASTPIN (-275 -1375) $PN 2
J 0
(-265 -1395);
DISPLAY 0.787234 (-265 -1395);
PAINT MONO (-265 -1395);
DISPLAY INVISIBLE (-265 -1395);
FORCEADD UNIVERSAL_GND..1
(-275 -1525);
FORCEPROP 3 LASTPIN (-275 -1475) SIG_NAME GND\g
J 0
(-265 -1465);
DISPLAY 0.659574 (-265 -1465);
PAINT MONO (-265 -1465);
DISPLAY INVISIBLE (-265 -1465);
FORCEPROP 1 LAST HDL_POWER GND
J 1
(-250 -1600);
DISPLAY 0.872340 (-250 -1600);
PAINT GREEN (-250 -1600);
DISPLAY INVISIBLE (-250 -1600);
FORCEPROP 2 LAST CDS_LIB logical_power
J 0
(-275 -1525);
DISPLAY INVISIBLE (-275 -1525);
FORCEPROP 1 LAST PATH I15
J 0
(-200 -1525);
DISPLAY 0.872340 (-200 -1525);
PAINT AQUA (-200 -1525);
DISPLAY INVISIBLE (-200 -1525);
FORCEADD Q_CAP..1
(175 -1275);
FORCEPROP 1 LAST PART_NUMBER CH4104K1B00
J 0
(225 -1425);
DISPLAY 0.617021 (225 -1425);
PAINT BLUE (225 -1425);
DISPLAY INVISIBLE (225 -1425);
FORCEPROP 1 LAST VALUE 0.1UF
J 0
(225 -1225);
DISPLAY 0.617021 (225 -1225);
PAINT SKYBLUE (225 -1225);
FORCEPROP 1 LAST MATERIAL X7R
J 0
(225 -1375);
DISPLAY 0.617021 (225 -1375);
PAINT SKYBLUE (225 -1375);
FORCEPROP 1 LAST VOLTAGE 25V
J 0
(225 -1275);
DISPLAY 0.617021 (225 -1275);
PAINT SKYBLUE (225 -1275);
FORCEPROP 1 LAST PACK_TYPE 0402
J 0
(225 -1475);
DISPLAY 0.617021 (225 -1475);
PAINT SKYBLUE (225 -1475);
FORCEPROP 1 LAST TOLERANCE 10%
J 0
(225 -1325);
DISPLAY 0.617021 (225 -1325);
PAINT SKYBLUE (225 -1325);
FORCEPROP 1 LAST LOCATION PC1221
J 0
(225 -1175);
DISPLAY 0.617021 (225 -1175);
PAINT AQUA (225 -1175);
FORCEPROP 1 LASTPIN (175 -1175) $PN 1
J 0
(185 -1195);
DISPLAY 0.617021 (185 -1195);
PAINT MONO (185 -1195);
FORCEPROP 1 LASTPIN (175 -1375) $PN 2
J 0
(185 -1395);
DISPLAY 0.617021 (185 -1395);
PAINT MONO (185 -1395);
FORCEPROP 2 LAST CDS_LIB pure_quanta
J 0
(175 -1275);
DISPLAY INVISIBLE (175 -1275);
FORCEPROP 1 LAST PATH I16
J 0
(225 -1125);
DISPLAY 0.978723 (225 -1125);
PAINT WHITE (225 -1125);
DISPLAY INVISIBLE (225 -1125);
FORCEPROP 2 LAST $SEC 1
J 0
(225 -1075);
DISPLAY 0.680851 (225 -1075);
PAINT MONO (225 -1075);
DISPLAY INVISIBLE (225 -1075);
FORCEPROP 2 LAST CDS_SEC 1
J 0
(225 -1075);
DISPLAY 1.021277 (225 -1075);
DISPLAY INVISIBLE (225 -1075);
FORCEADD GND..1
(-4900 175);
FORCEPROP 3 LASTPIN (-4900 225) SIG_NAME GND\g
J 0
(-4890 235);
DISPLAY 0.659574 (-4890 235);
PAINT MONO (-4890 235);
DISPLAY INVISIBLE (-4890 235);
FORCEPROP 1 LAST HDL_POWER GND
J 0
(-4900 325);
DISPLAY 0.872340 (-4900 325);
PAINT GREEN (-4900 325);
DISPLAY INVISIBLE (-4900 325);
FORCEPROP 1 LAST SIZE 1B
J 0
(-4825 125);
DISPLAY 0.872340 (-4825 125);
PAINT AQUA (-4825 125);
DISPLAY INVISIBLE (-4825 125);
FORCEPROP 2 LAST CDS_LIB logical_power
J 0
(-4900 175);
DISPLAY INVISIBLE (-4900 175);
FORCEPROP 1 LAST PATH I17
J 0
(-4825 175);
DISPLAY 0.872340 (-4825 175);
PAINT AQUA (-4825 175);
DISPLAY INVISIBLE (-4825 175);
FORCEADD Q_CAP..1
(-4900 425);
FORCEPROP 1 LAST PART_NUMBER CH4106K1B01
J 0
(-4850 275);
DISPLAY 0.787234 (-4850 275);
DISPLAY INVISIBLE (-4850 275);
FORCEPROP 1 LAST MATERIAL X7R
J 0
(-4850 325);
DISPLAY 0.787234 (-4850 325);
FORCEPROP 1 LAST PACK_TYPE C0402
J 0
(-4850 225);
DISPLAY 0.787234 (-4850 225);
FORCEPROP 1 LAST VOLTAGE 50V
J 0
(-4850 425);
DISPLAY 0.787234 (-4850 425);
FORCEPROP 1 LAST TOLERANCE 10%
J 0
(-4850 375);
DISPLAY 0.787234 (-4850 375);
FORCEPROP 1 LAST VALUE 100NF
J 0
(-4850 475);
DISPLAY 0.787234 (-4850 475);
FORCEPROP 1 LAST LOCATION PC1650
J 0
(-4850 525);
DISPLAY 0.787234 (-4850 525);
FORCEPROP 1 LASTPIN (-4900 525) $PN 1
J 0
(-4890 505);
DISPLAY 0.787234 (-4890 505);
PAINT MONO (-4890 505);
FORCEPROP 1 LASTPIN (-4900 325) $PN 2
J 0
(-4890 305);
DISPLAY 0.787234 (-4890 305);
PAINT MONO (-4890 305);
FORCEPROP 2 LAST CDS_LIB pure_quanta
J 0
(-4900 425);
DISPLAY INVISIBLE (-4900 425);
FORCEPROP 1 LAST PATH I18
J 0
(-4850 575);
DISPLAY 0.978723 (-4850 575);
PAINT WHITE (-4850 575);
DISPLAY INVISIBLE (-4850 575);
FORCEPROP 0 LAST $SEC 1
J 0
(-4850 575);
DISPLAY 0.680851 (-4850 575);
PAINT MONO (-4850 575);
DISPLAY INVISIBLE (-4850 575);
FORCEPROP 0 LAST CDS_SEC 1
J 0
(-4850 575);
DISPLAY 1.021277 (-4850 575);
DISPLAY INVISIBLE (-4850 575);
FORCEADD Q_INDUCTOR..1
(-4575 650);
FORCEPROP 1 LAST PART_NUMBER CV+10G0MZ04
J 0
(-4700 760);
DISPLAY 0.617021 (-4700 760);
PAINT BLUE (-4700 760);
DISPLAY INVISIBLE (-4700 760);
FORCEPROP 2 LAST PACK_TYPE SMLF
J 0
(-4700 900);
DISPLAY 0.617021 (-4700 900);
PAINT SKYBLUE (-4700 900);
FORCEPROP 2 LAST VALUE 100NH/16A
J 0
(-4700 850);
DISPLAY 0.617021 (-4700 850);
PAINT SKYBLUE (-4700 850);
FORCEPROP 1 LAST MATERIAL IND
J 0
(-4700 705);
DISPLAY 0.617021 (-4700 705);
PAINT SKYBLUE (-4700 705);
FORCEPROP 1 LAST LOCATION PL110
J 0
(-4700 810);
DISPLAY 0.617021 (-4700 810);
PAINT AQUA (-4700 810);
FORCEPROP 2 LASTPIN (-4675 625) $PN 1
J 2
(-4685 635);
DISPLAY 0.617021 (-4685 635);
FORCEPROP 2 LASTPIN (-4475 625) $PN 2
J 0
(-4465 635);
DISPLAY 0.617021 (-4465 635);
FORCEPROP 2 LAST CDS_LIB pure_quanta
J 0
(-4575 650);
PAINT MONO (-4575 650);
DISPLAY INVISIBLE (-4575 650);
FORCEPROP 1 LAST NEEDS_NO_SIZE TRUE
J 0
(-4575 650);
DISPLAY 0.468085 (-4575 650);
PAINT GREEN (-4575 650);
DISPLAY INVISIBLE (-4575 650);
FORCEPROP 1 LAST PATH I19
J 0
(-4500 705);
DISPLAY 0.723404 (-4500 705);
PAINT GREEN (-4500 705);
DISPLAY INVISIBLE (-4500 705);
FORCEPROP 2 LAST $SEC 1
J 0
(-4700 950);
DISPLAY 0.680851 (-4700 950);
PAINT MONO (-4700 950);
DISPLAY INVISIBLE (-4700 950);
FORCEPROP 2 LAST CDS_SEC 1
J 0
(-4700 950);
DISPLAY 1.021277 (-4700 950);
DISPLAY INVISIBLE (-4700 950);
FORCEADD Q_CAP..1
(-3150 -1425);
FORCEPROP 1 LAST PART_NUMBER CH5104KEB02
J 0
(-3100 -1575);
DISPLAY 0.617021 (-3100 -1575);
PAINT BLUE (-3100 -1575);
DISPLAY INVISIBLE (-3100 -1575);
FORCEPROP 1 LAST PACK_TYPE C0402
J 0
(-3100 -1625);
DISPLAY 0.617021 (-3100 -1625);
PAINT SKYBLUE (-3100 -1625);
FORCEPROP 1 LAST VALUE 1UF
J 0
(-3100 -1375);
DISPLAY 0.617021 (-3100 -1375);
PAINT SKYBLUE (-3100 -1375);
FORCEPROP 1 LAST TOLERANCE 10%
J 0
(-3100 -1475);
DISPLAY 0.617021 (-3100 -1475);
PAINT SKYBLUE (-3100 -1475);
FORCEPROP 1 LAST VOLTAGE 25V
J 0
(-3100 -1425);
DISPLAY 0.617021 (-3100 -1425);
PAINT SKYBLUE (-3100 -1425);
FORCEPROP 1 LAST MATERIAL X6S
J 0
(-3100 -1525);
DISPLAY 0.617021 (-3100 -1525);
PAINT SKYBLUE (-3100 -1525);
FORCEPROP 1 LAST LOCATION PC113
J 0
(-3100 -1325);
DISPLAY 0.617021 (-3100 -1325);
PAINT AQUA (-3100 -1325);
FORCEPROP 1 LASTPIN (-3150 -1325) $PN 1
J 0
(-3140 -1345);
DISPLAY 0.617021 (-3140 -1345);
FORCEPROP 1 LASTPIN (-3150 -1525) $PN 2
J 0
(-3140 -1545);
DISPLAY 0.617021 (-3140 -1545);
FORCEPROP 2 LAST CDS_LIB pure_quanta
J 0
(-3150 -1425);
DISPLAY INVISIBLE (-3150 -1425);
FORCEPROP 2 LAST SEC_TYPE C0402
J 0
(-3100 -1225);
DISPLAY 1.021277 (-3100 -1225);
DISPLAY INVISIBLE (-3100 -1225);
FORCEPROP 2 LAST BOM_COST VR_PCH
J 0
(-3100 -1275);
DISPLAY 0.680851 (-3100 -1275);
DISPLAY INVISIBLE (-3100 -1275);
FORCEPROP 1 LAST PATH I2
J 0
(-3100 -1275);
DISPLAY 0.978723 (-3100 -1275);
PAINT WHITE (-3100 -1275);
DISPLAY INVISIBLE (-3100 -1275);
FORCEPROP 2 LAST SEC 1
J 0
(-3100 -1225);
DISPLAY 0.680851 (-3100 -1225);
PAINT MONO (-3100 -1225);
DISPLAY INVISIBLE (-3100 -1225);
FORCEADD VCCAUX15..1
(-4900 1050);
FORCEPROP 3 LASTPIN (-4900 1000) SIG_NAME P12V_AUX\g
J 0
(-4890 1010);
DISPLAY 0.659574 (-4890 1010);
PAINT MONO (-4890 1010);
DISPLAY INVISIBLE (-4890 1010);
FORCEPROP 1 LAST HDL_POWER P12V_AUX
J 1
(-4900 1092);
DISPLAY 0.617021 (-4900 1092);
PAINT GREEN (-4900 1092);
FORCEPROP 2 LAST CDS_LIB logical_power
J 0
(-4900 1050);
PAINT MONO (-4900 1050);
DISPLAY INVISIBLE (-4900 1050);
FORCEPROP 2 LAST BOM_COST VR_PCH
J 0
(-4900 1125);
DISPLAY 0.680851 (-4900 1125);
DISPLAY INVISIBLE (-4900 1125);
FORCEPROP 1 LAST PATH I20
J 0
(-4850 1075);
DISPLAY 0.872340 (-4850 1075);
PAINT AQUA (-4850 1075);
DISPLAY INVISIBLE (-4850 1075);
FORCEADD OFFPAGE..4
R 2
(-4100 -350);
FORCEPROP 2 LAST $XR0 214 
J 0
(-4382 -350);
DISPLAY 0.638298 (-4382 -350);
PAINT MONO (-4382 -350);
FORCEPROP 1 LAST COMMENT_BODY TRUE
J 2
(-4075 -450);
DISPLAY 0.872340 (-4075 -450);
PAINT GREEN (-4075 -450);
DISPLAY INVISIBLE (-4075 -450);
FORCEPROP 1 LAST OFFPAGE TRUE
J 2
(-4425 -475);
DISPLAY 0.872340 (-4425 -475);
PAINT GREEN (-4425 -475);
DISPLAY INVISIBLE (-4425 -475);
FORCEPROP 2 LAST CDS_LIB standard
J 0
(-4100 -350);
DISPLAY INVISIBLE (-4100 -350);
FORCEPROP 2 LAST PATH I21
J 0
(-4375 -300);
DISPLAY 1.021277 (-4375 -300);
DISPLAY INVISIBLE (-4375 -300);
FORCEADD UNIVERSAL_GND..1
(-4325 50);
FORCEPROP 3 LASTPIN (-4325 100) SIG_NAME GND\g
J 0
(-4315 110);
DISPLAY 0.659574 (-4315 110);
PAINT MONO (-4315 110);
DISPLAY INVISIBLE (-4315 110);
FORCEPROP 1 LAST HDL_POWER GND
J 1
(-4300 -25);
DISPLAY 0.872340 (-4300 -25);
PAINT GREEN (-4300 -25);
DISPLAY INVISIBLE (-4300 -25);
FORCEPROP 2 LAST CDS_LIB logical_power
J 0
(-4325 50);
PAINT MONO (-4325 50);
DISPLAY INVISIBLE (-4325 50);
FORCEPROP 1 LAST PATH I22
J 0
(-4250 50);
DISPLAY 0.872340 (-4250 50);
PAINT AQUA (-4250 50);
DISPLAY INVISIBLE (-4250 50);
FORCEADD Q_CAPP..1
(-4325 375);
FORCEPROP 1 LAST PART_NUMBER CC71003MZ30
J 0
(-4275 175);
DISPLAY 0.978723 (-4275 175);
DISPLAY INVISIBLE (-4275 175);
FORCEPROP 1 LAST TOLERANCE 20%
J 0
(-4275 375);
DISPLAY 0.978723 (-4275 375);
FORCEPROP 1 LAST MATERIAL OSCON
J 0
(-4275 275);
DISPLAY 0.978723 (-4275 275);
FORCEPROP 1 LAST PACK_TYPE SMLF
J 0
(-4275 225);
DISPLAY 0.978723 (-4275 225);
FORCEPROP 1 LAST VOLTAGE 16V
J 0
(-4275 325);
DISPLAY 0.978723 (-4275 325);
FORCEPROP 1 LAST VALUE 100UF
J 0
(-4275 425);
DISPLAY 0.978723 (-4275 425);
FORCEPROP 1 LAST $LOCATION PC1215
J 0
(-4275 475);
DISPLAY 0.978723 (-4275 475);
FORCEPROP 1 LASTPIN (-4325 475) $PN 1
J 0
(-4315 460);
DISPLAY 0.787234 (-4315 460);
PAINT MONO (-4315 460);
FORCEPROP 1 LASTPIN (-4325 275) $PN 2
J 0
(-4315 260);
DISPLAY 0.787234 (-4315 260);
PAINT MONO (-4315 260);
FORCEPROP 2 LAST BOM_COST VR_SYSTEM 
J 0
(-4275 525);
DISPLAY 0.680851 (-4275 525);
DISPLAY INVISIBLE (-4275 525);
FORCEPROP 2 LAST CDS_LIB pure_quanta
J 0
(-4325 375);
DISPLAY INVISIBLE (-4325 375);
FORCEPROP 1 LAST PATH I23
J 0
(-4275 525);
DISPLAY 0.978723 (-4275 525);
DISPLAY INVISIBLE (-4275 525);
FORCEPROP 0 LAST CDS_LOCATION PC1215
J 0
(-4275 525);
DISPLAY 1.021277 (-4275 525);
DISPLAY INVISIBLE (-4275 525);
FORCEPROP 0 LAST $SEC 1
J 0
(-4275 525);
DISPLAY 0.680851 (-4275 525);
PAINT MONO (-4275 525);
DISPLAY INVISIBLE (-4275 525);
FORCEPROP 0 LAST CDS_SEC 1
J 0
(-4275 525);
DISPLAY 0.680851 (-4275 525);
DISPLAY INVISIBLE (-4275 525);
FORCEADD VCCAUX15..1
(-3750 0);
FORCEPROP 3 LASTPIN (-3750 -50) SIG_NAME P3V3_AUX\g
J 0
(-3740 -40);
DISPLAY 0.659574 (-3740 -40);
PAINT MONO (-3740 -40);
DISPLAY INVISIBLE (-3740 -40);
FORCEPROP 1 LAST HDL_POWER P3V3_AUX
J 1
(-3750 42);
DISPLAY 0.617021 (-3750 42);
PAINT GREEN (-3750 42);
FORCEPROP 2 LAST BOM_COST VR_PCH
J 0
(-3750 75);
DISPLAY 0.680851 (-3750 75);
DISPLAY INVISIBLE (-3750 75);
FORCEPROP 2 LAST CDS_LIB logical_power
J 0
(-3750 0);
PAINT MONO (-3750 0);
DISPLAY INVISIBLE (-3750 0);
FORCEPROP 1 LAST PATH I24
J 0
(-3700 25);
DISPLAY 0.872340 (-3700 25);
PAINT AQUA (-3700 25);
DISPLAY INVISIBLE (-3700 25);
FORCEADD Q_CAP..1
(-3725 375);
FORCEPROP 1 LAST PART_NUMBER CH6223MEA01
J 0
(-3675 225);
DISPLAY 0.617021 (-3675 225);
PAINT BLUE (-3675 225);
DISPLAY INVISIBLE (-3675 225);
FORCEPROP 1 LAST TOLERANCE 20%
J 0
(-3675 325);
DISPLAY 0.617021 (-3675 325);
PAINT SKYBLUE (-3675 325);
FORCEPROP 1 LAST PACK_TYPE C0805
J 0
(-3675 175);
DISPLAY 0.617021 (-3675 175);
PAINT SKYBLUE (-3675 175);
FORCEPROP 1 LAST MATERIAL X6S
J 0
(-3675 275);
DISPLAY 0.617021 (-3675 275);
PAINT SKYBLUE (-3675 275);
FORCEPROP 1 LAST VOLTAGE 16V
J 0
(-3675 375);
DISPLAY 0.617021 (-3675 375);
PAINT SKYBLUE (-3675 375);
FORCEPROP 1 LAST VALUE 22UF
J 0
(-3675 425);
DISPLAY 0.617021 (-3675 425);
PAINT SKYBLUE (-3675 425);
FORCEPROP 1 LAST LOCATION PC1216
J 0
(-3675 475);
DISPLAY 0.617021 (-3675 475);
PAINT AQUA (-3675 475);
FORCEPROP 1 LASTPIN (-3725 475) $PN 1
J 0
(-3715 455);
DISPLAY 0.617021 (-3715 455);
PAINT MONO (-3715 455);
FORCEPROP 1 LASTPIN (-3725 275) $PN 2
J 0
(-3715 255);
DISPLAY 0.617021 (-3715 255);
PAINT MONO (-3715 255);
FORCEPROP 2 LAST CDS_LIB pure_quanta
J 0
(-3725 375);
DISPLAY INVISIBLE (-3725 375);
FORCEPROP 2 LAST BOM_COST VR_PCH
J 0
(-3675 525);
DISPLAY 0.680851 (-3675 525);
DISPLAY INVISIBLE (-3675 525);
FORCEPROP 1 LAST PATH I25
J 0
(-3675 525);
DISPLAY 0.978723 (-3675 525);
PAINT WHITE (-3675 525);
DISPLAY INVISIBLE (-3675 525);
FORCEPROP 2 LAST $SEC 1
J 0
(-3675 575);
DISPLAY 0.680851 (-3675 575);
PAINT MONO (-3675 575);
DISPLAY INVISIBLE (-3675 575);
FORCEPROP 2 LAST CDS_SEC 1
J 0
(-3675 575);
DISPLAY 1.021277 (-3675 575);
DISPLAY INVISIBLE (-3675 575);
FORCEADD Q_RES..1
(-2950 -75);
FORCEPROP 1 LAST PART_NUMBER CS31002FB08
J 0
(-3100 0);
DISPLAY 0.617021 (-3100 0);
PAINT BLUE (-3100 0);
DISPLAY INVISIBLE (-3100 0);
FORCEPROP 1 LAST WATTAGE 1/16W
J 2
(-2825 25);
DISPLAY 0.617021 (-2825 25);
PAINT SKYBLUE (-2825 25);
FORCEPROP 1 LAST MATERIAL EMPTY
J 0
(-2700 -75);
DISPLAY 0.617021 (-2700 -75);
PAINT RED (-2700 -75);
FORCEPROP 1 LAST TOLERANCE 1%
J 0
(-2775 -75);
DISPLAY 0.617021 (-2775 -75);
PAINT SKYBLUE (-2775 -75);
FORCEPROP 1 LAST PACK_TYPE 0402LF
J 0
(-3100 25);
DISPLAY 0.617021 (-3100 25);
PAINT SKYBLUE (-3100 25);
FORCEPROP 1 LAST VALUE 10K
J 2
(-2800 -75);
DISPLAY 0.617021 (-2800 -75);
PAINT SKYBLUE (-2800 -75);
FORCEPROP 1 LAST LOCATION PR1647
J 0
(-3200 -75);
DISPLAY 0.617021 (-3200 -75);
PAINT AQUA (-3200 -75);
FORCEPROP 1 LASTPIN (-3050 -75) $PN 1
J 0
(-3038 -63);
DISPLAY 0.617021 (-3038 -63);
FORCEPROP 1 LASTPIN (-2850 -75) $PN 2
J 0
(-2888 -63);
DISPLAY 0.617021 (-2888 -63);
FORCEPROP 2 LAST CDS_LIB pure_quanta
J 0
(-2950 -75);
PAINT MONO (-2950 -75);
DISPLAY INVISIBLE (-2950 -75);
FORCEPROP 1 LAST PATH I26
J 0
(-3000 75);
DISPLAY 0.978723 (-3000 75);
PAINT WHITE (-3000 75);
DISPLAY INVISIBLE (-3000 75);
FORCEPROP 2 LAST $SEC 1
J 0
(-3000 125);
DISPLAY 0.680851 (-3000 125);
PAINT MONO (-3000 125);
DISPLAY INVISIBLE (-3000 125);
FORCEPROP 2 LAST CDS_SEC 1
J 0
(-3000 125);
DISPLAY 1.021277 (-3000 125);
DISPLAY INVISIBLE (-3000 125);
FORCEADD Q_RES..1
(-2950 -350);
FORCEPROP 1 LAST PART_NUMBER CS00002JB13
J 0
(-3000 -300);
DISPLAY 0.404255 (-3000 -300);
PAINT BLUE (-3000 -300);
DISPLAY INVISIBLE (-3000 -300);
FORCEPROP 1 LAST VALUE 0
J 2
(-2800 -350);
DISPLAY 0.617021 (-2800 -350);
PAINT SKYBLUE (-2800 -350);
FORCEPROP 1 LAST MATERIAL CHIP
J 0
(-2700 -350);
DISPLAY 0.617021 (-2700 -350);
PAINT SKYBLUE (-2700 -350);
FORCEPROP 1 LAST TOLERANCE 5%
J 0
(-2775 -350);
DISPLAY 0.617021 (-2775 -350);
PAINT SKYBLUE (-2775 -350);
FORCEPROP 1 LAST LOCATION R1389
J 0
(-3200 -350);
DISPLAY 0.617021 (-3200 -350);
PAINT AQUA (-3200 -350);
FORCEPROP 1 LASTPIN (-3050 -350) $PN 1
J 0
(-3038 -338);
DISPLAY 0.617021 (-3038 -338);
FORCEPROP 1 LASTPIN (-2850 -350) $PN 2
J 0
(-2888 -338);
DISPLAY 0.617021 (-2888 -338);
FORCEPROP 2 LAST CDS_LIB pure_quanta
J 0
(-2950 -350);
PAINT MONO (-2950 -350);
DISPLAY INVISIBLE (-2950 -350);
FORCEPROP 1 LAST WATTAGE 1/16W
J 2
(-2775 -275);
DISPLAY 0.404255 (-2775 -275);
PAINT SKYBLUE (-2775 -275);
DISPLAY INVISIBLE (-2775 -275);
FORCEPROP 1 LAST PACK_TYPE 0402LF
J 0
(-3000 -250);
DISPLAY 0.404255 (-3000 -250);
PAINT SKYBLUE (-3000 -250);
DISPLAY INVISIBLE (-3000 -250);
FORCEPROP 1 LAST PATH I27
J 0
(-3000 -200);
DISPLAY 0.978723 (-3000 -200);
PAINT WHITE (-3000 -200);
DISPLAY INVISIBLE (-3000 -200);
FORCEPROP 2 LAST $SEC 1
J 0
(-3000 -150);
DISPLAY 0.680851 (-3000 -150);
PAINT MONO (-3000 -150);
DISPLAY INVISIBLE (-3000 -150);
FORCEPROP 2 LAST CDS_SEC 1
J 0
(-3000 -150);
DISPLAY 1.021277 (-3000 -150);
DISPLAY INVISIBLE (-3000 -150);
FORCEADD Q_CAP..1
(-3275 375);
FORCEPROP 1 LAST PART_NUMBER CH6223MEA01
J 0
(-3225 225);
DISPLAY 0.617021 (-3225 225);
PAINT BLUE (-3225 225);
DISPLAY INVISIBLE (-3225 225);
FORCEPROP 1 LAST MATERIAL X6S
J 0
(-3225 275);
DISPLAY 0.617021 (-3225 275);
PAINT SKYBLUE (-3225 275);
FORCEPROP 1 LAST TOLERANCE 20%
J 0
(-3225 325);
DISPLAY 0.617021 (-3225 325);
PAINT SKYBLUE (-3225 325);
FORCEPROP 1 LAST PACK_TYPE C0805
J 0
(-3225 175);
DISPLAY 0.617021 (-3225 175);
PAINT SKYBLUE (-3225 175);
FORCEPROP 1 LAST VALUE 22UF
J 0
(-3225 425);
DISPLAY 0.617021 (-3225 425);
PAINT SKYBLUE (-3225 425);
FORCEPROP 1 LAST VOLTAGE 16V
J 0
(-3225 375);
DISPLAY 0.617021 (-3225 375);
PAINT SKYBLUE (-3225 375);
FORCEPROP 1 LAST LOCATION PC1217
J 0
(-3225 475);
DISPLAY 0.617021 (-3225 475);
PAINT AQUA (-3225 475);
FORCEPROP 1 LASTPIN (-3275 475) $PN 1
J 0
(-3265 455);
DISPLAY 0.617021 (-3265 455);
PAINT MONO (-3265 455);
FORCEPROP 1 LASTPIN (-3275 275) $PN 2
J 0
(-3265 255);
DISPLAY 0.617021 (-3265 255);
PAINT MONO (-3265 255);
FORCEPROP 2 LAST BOM_COST VR_PCH
J 0
(-3225 525);
DISPLAY 0.680851 (-3225 525);
DISPLAY INVISIBLE (-3225 525);
FORCEPROP 2 LAST CDS_LIB pure_quanta
J 0
(-3275 375);
DISPLAY INVISIBLE (-3275 375);
FORCEPROP 1 LAST PATH I28
J 0
(-3225 525);
DISPLAY 0.978723 (-3225 525);
PAINT WHITE (-3225 525);
DISPLAY INVISIBLE (-3225 525);
FORCEPROP 2 LAST $SEC 1
J 0
(-3225 575);
DISPLAY 0.680851 (-3225 575);
PAINT MONO (-3225 575);
DISPLAY INVISIBLE (-3225 575);
FORCEPROP 2 LAST CDS_SEC 1
J 0
(-3225 575);
DISPLAY 1.021277 (-3225 575);
DISPLAY INVISIBLE (-3225 575);
FORCEADD Q_CAP..1
(-2850 375);
FORCEPROP 1 LAST PART_NUMBER CH6223MEA01
J 0
(-2800 225);
DISPLAY 0.617021 (-2800 225);
PAINT BLUE (-2800 225);
DISPLAY INVISIBLE (-2800 225);
FORCEPROP 1 LAST MATERIAL X6S
J 0
(-2800 275);
DISPLAY 0.617021 (-2800 275);
PAINT SKYBLUE (-2800 275);
FORCEPROP 1 LAST TOLERANCE 20%
J 0
(-2800 325);
DISPLAY 0.617021 (-2800 325);
PAINT SKYBLUE (-2800 325);
FORCEPROP 1 LAST VALUE 22UF
J 0
(-2800 425);
DISPLAY 0.617021 (-2800 425);
PAINT SKYBLUE (-2800 425);
FORCEPROP 1 LAST VOLTAGE 16V
J 0
(-2800 375);
DISPLAY 0.617021 (-2800 375);
PAINT SKYBLUE (-2800 375);
FORCEPROP 1 LAST PACK_TYPE C0805
J 0
(-2800 175);
DISPLAY 0.617021 (-2800 175);
PAINT SKYBLUE (-2800 175);
FORCEPROP 1 LAST LOCATION PC1218
J 0
(-2800 475);
DISPLAY 0.617021 (-2800 475);
PAINT AQUA (-2800 475);
FORCEPROP 1 LASTPIN (-2850 475) $PN 1
J 0
(-2840 455);
DISPLAY 0.617021 (-2840 455);
PAINT MONO (-2840 455);
FORCEPROP 1 LASTPIN (-2850 275) $PN 2
J 0
(-2840 255);
DISPLAY 0.617021 (-2840 255);
PAINT MONO (-2840 255);
FORCEPROP 2 LAST BOM_COST VR_PCH
J 0
(-2800 525);
DISPLAY 0.680851 (-2800 525);
DISPLAY INVISIBLE (-2800 525);
FORCEPROP 2 LAST CDS_LIB pure_quanta
J 0
(-2850 375);
DISPLAY INVISIBLE (-2850 375);
FORCEPROP 1 LAST PATH I29
J 0
(-2800 525);
DISPLAY 0.978723 (-2800 525);
PAINT WHITE (-2800 525);
DISPLAY INVISIBLE (-2800 525);
FORCEPROP 2 LAST $SEC 1
J 0
(-2800 575);
DISPLAY 0.680851 (-2800 575);
PAINT MONO (-2800 575);
DISPLAY INVISIBLE (-2800 575);
FORCEPROP 2 LAST CDS_SEC 1
J 0
(-2800 575);
DISPLAY 1.021277 (-2800 575);
DISPLAY INVISIBLE (-2800 575);
FORCEADD Q_RES..2
(-3150 -1000);
FORCEPROP 1 LAST PART_NUMBER CS00002JB13
J 0
(-3110 -1125);
DISPLAY 0.617021 (-3110 -1125);
PAINT BLUE (-3110 -1125);
DISPLAY INVISIBLE (-3110 -1125);
FORCEPROP 1 LAST VALUE 0
J 0
(-3105 -925);
DISPLAY 0.617021 (-3105 -925);
PAINT SKYBLUE (-3105 -925);
FORCEPROP 1 LAST MATERIAL CHIP
J 0
(-3110 -1075);
DISPLAY 0.617021 (-3110 -1075);
PAINT SKYBLUE (-3110 -1075);
FORCEPROP 1 LAST PACK_TYPE 0402LF
J 0
(-3110 -1175);
DISPLAY 0.617021 (-3110 -1175);
PAINT SKYBLUE (-3110 -1175);
FORCEPROP 1 LAST TOLERANCE 5%
J 0
(-3105 -975);
DISPLAY 0.617021 (-3105 -975);
PAINT SKYBLUE (-3105 -975);
FORCEPROP 1 LAST WATTAGE 1/16W
J 0
(-3110 -1025);
DISPLAY 0.617021 (-3110 -1025);
PAINT SKYBLUE (-3110 -1025);
FORCEPROP 1 LAST LOCATION PR1326
J 0
(-3105 -875);
DISPLAY 0.617021 (-3105 -875);
PAINT AQUA (-3105 -875);
FORCEPROP 1 LASTPIN (-3150 -900) $PN 1
J 0
(-3145 -938);
DISPLAY 0.617021 (-3145 -938);
FORCEPROP 1 LASTPIN (-3150 -1100) $PN 2
J 0
(-3145 -1090);
DISPLAY 0.617021 (-3145 -1090);
FORCEPROP 2 LAST CDS_LIB pure_quanta
J 0
(-3150 -1000);
PAINT MONO (-3150 -1000);
DISPLAY INVISIBLE (-3150 -1000);
FORCEPROP 1 LAST PATH I3
J 0
(-3100 -825);
DISPLAY 0.978723 (-3100 -825);
PAINT WHITE (-3100 -825);
DISPLAY INVISIBLE (-3100 -825);
FORCEPROP 2 LAST $SEC 1
J 0
(-3100 -775);
DISPLAY 0.680851 (-3100 -775);
PAINT MONO (-3100 -775);
DISPLAY INVISIBLE (-3100 -775);
FORCEPROP 2 LAST CDS_SEC 1
J 0
(-3100 -775);
DISPLAY 1.021277 (-3100 -775);
DISPLAY INVISIBLE (-3100 -775);
FORCEADD Q_CAP..1
(-2425 375);
FORCEPROP 1 LAST PART_NUMBER CH5103KEB01
J 0
(-2375 225);
DISPLAY 0.617021 (-2375 225);
PAINT BLUE (-2375 225);
DISPLAY INVISIBLE (-2375 225);
FORCEPROP 1 LAST PACK_TYPE C0402
J 0
(-2375 175);
DISPLAY 0.617021 (-2375 175);
PAINT SKYBLUE (-2375 175);
FORCEPROP 1 LAST TOLERANCE 10%
J 0
(-2375 325);
DISPLAY 0.617021 (-2375 325);
PAINT SKYBLUE (-2375 325);
FORCEPROP 1 LAST MATERIAL X6S
J 0
(-2375 275);
DISPLAY 0.617021 (-2375 275);
PAINT SKYBLUE (-2375 275);
FORCEPROP 1 LAST VOLTAGE 16V
J 0
(-2375 375);
DISPLAY 0.617021 (-2375 375);
PAINT SKYBLUE (-2375 375);
FORCEPROP 1 LAST VALUE 1UF
J 0
(-2375 425);
DISPLAY 0.617021 (-2375 425);
PAINT SKYBLUE (-2375 425);
FORCEPROP 1 LAST LOCATION PC1219
J 0
(-2375 475);
DISPLAY 0.617021 (-2375 475);
PAINT AQUA (-2375 475);
FORCEPROP 1 LASTPIN (-2425 475) $PN 1
J 0
(-2415 455);
DISPLAY 0.617021 (-2415 455);
PAINT MONO (-2415 455);
FORCEPROP 1 LASTPIN (-2425 275) $PN 2
J 0
(-2415 255);
DISPLAY 0.617021 (-2415 255);
PAINT MONO (-2415 255);
FORCEPROP 2 LAST CDS_LIB pure_quanta
J 0
(-2425 375);
DISPLAY INVISIBLE (-2425 375);
FORCEPROP 1 LAST PATH I30
J 0
(-2375 525);
DISPLAY 0.978723 (-2375 525);
PAINT WHITE (-2375 525);
DISPLAY INVISIBLE (-2375 525);
FORCEPROP 2 LAST $SEC 1
J 0
(-2375 575);
DISPLAY 0.680851 (-2375 575);
PAINT MONO (-2375 575);
DISPLAY INVISIBLE (-2375 575);
FORCEPROP 2 LAST CDS_SEC 1
J 0
(-2375 575);
DISPLAY 1.021277 (-2375 575);
DISPLAY INVISIBLE (-2375 575);
FORCEADD Q_CAP..1
(350 -125);
FORCEPROP 1 LAST PART_NUMBER CH4224K1B01
J 0
(400 -275);
DISPLAY 0.617021 (400 -275);
PAINT BLUE (400 -275);
DISPLAY INVISIBLE (400 -275);
FORCEPROP 1 LAST PACK_TYPE C0402
J 0
(400 -325);
DISPLAY 0.617021 (400 -325);
PAINT SKYBLUE (400 -325);
FORCEPROP 1 LAST VOLTAGE 25V
J 0
(400 -125);
DISPLAY 0.617021 (400 -125);
PAINT SKYBLUE (400 -125);
FORCEPROP 1 LAST VALUE 0.22UF
J 0
(400 -75);
DISPLAY 0.617021 (400 -75);
PAINT SKYBLUE (400 -75);
FORCEPROP 1 LAST MATERIAL X7R
J 0
(400 -225);
DISPLAY 0.617021 (400 -225);
PAINT SKYBLUE (400 -225);
FORCEPROP 1 LAST TOLERANCE 10%
J 0
(400 -175);
DISPLAY 0.617021 (400 -175);
PAINT SKYBLUE (400 -175);
FORCEPROP 1 LAST LOCATION PC1222
J 0
(400 -25);
DISPLAY 0.617021 (400 -25);
PAINT AQUA (400 -25);
FORCEPROP 1 LASTPIN (350 -25) $PN 1
J 0
(360 -45);
DISPLAY 0.617021 (360 -45);
PAINT MONO (360 -45);
FORCEPROP 1 LASTPIN (350 -225) $PN 2
J 0
(360 -245);
DISPLAY 0.617021 (360 -245);
PAINT MONO (360 -245);
FORCEPROP 2 LAST CDS_LIB pure_quanta
J 0
(350 -125);
DISPLAY INVISIBLE (350 -125);
FORCEPROP 1 LAST PATH I31
J 0
(400 25);
DISPLAY 0.978723 (400 25);
PAINT WHITE (400 25);
DISPLAY INVISIBLE (400 25);
FORCEPROP 2 LAST $SEC 1
J 0
(400 75);
DISPLAY 0.680851 (400 75);
PAINT MONO (400 75);
DISPLAY INVISIBLE (400 75);
FORCEPROP 2 LAST CDS_SEC 1
J 0
(400 75);
DISPLAY 1.021277 (400 75);
DISPLAY INVISIBLE (400 75);
FORCEADD Q_RES..2
(450 525);
FORCEPROP 1 LAST PART_NUMBER CS31002FB08
J 0
(490 400);
DISPLAY 0.617021 (490 400);
PAINT BLUE (490 400);
DISPLAY INVISIBLE (490 400);
FORCEPROP 1 LAST MATERIAL CHIP
J 0
(490 450);
DISPLAY 0.617021 (490 450);
PAINT SKYBLUE (490 450);
FORCEPROP 1 LAST WATTAGE 1/16W
J 0
(490 500);
DISPLAY 0.617021 (490 500);
PAINT SKYBLUE (490 500);
FORCEPROP 1 LAST TOLERANCE 1%
J 0
(495 550);
DISPLAY 0.617021 (495 550);
PAINT SKYBLUE (495 550);
FORCEPROP 1 LAST VALUE 10K
J 0
(495 600);
DISPLAY 0.617021 (495 600);
PAINT SKYBLUE (495 600);
FORCEPROP 1 LAST PACK_TYPE 0402LF
J 0
(490 350);
DISPLAY 0.617021 (490 350);
PAINT SKYBLUE (490 350);
FORCEPROP 1 LAST LOCATION R2357
J 0
(495 650);
DISPLAY 0.617021 (495 650);
PAINT AQUA (495 650);
FORCEPROP 1 LASTPIN (450 625) $PN 1
J 0
(455 587);
DISPLAY 0.617021 (455 587);
FORCEPROP 1 LASTPIN (450 425) $PN 2
J 0
(455 435);
DISPLAY 0.617021 (455 435);
FORCEPROP 2 LAST CDS_LIB pure_quanta
J 0
(450 525);
DISPLAY INVISIBLE (450 525);
FORCEPROP 2 LAST BOM_COST VR_PCH
J 0
(500 700);
DISPLAY 0.680851 (500 700);
DISPLAY INVISIBLE (500 700);
FORCEPROP 1 LAST PATH I32
J 0
(500 700);
DISPLAY 0.978723 (500 700);
PAINT WHITE (500 700);
DISPLAY INVISIBLE (500 700);
FORCEPROP 0 LAST $SEC 1
J 0
(500 750);
DISPLAY 0.680851 (500 750);
PAINT MONO (500 750);
DISPLAY INVISIBLE (500 750);
FORCEPROP 0 LAST CDS_SEC 1
J 0
(500 750);
DISPLAY 0.680851 (500 750);
DISPLAY INVISIBLE (500 750);
FORCEADD UNIVERSAL_POWER..1
(450 775);
FORCEPROP 3 LASTPIN (450 725) SIG_NAME P3V3_AUX\g
J 0
(460 735);
DISPLAY 0.659574 (460 735);
PAINT MONO (460 735);
DISPLAY INVISIBLE (460 735);
FORCEPROP 1 LAST HDL_POWER P3V3_AUX
J 1
(450 825);
DISPLAY 0.617021 (450 825);
PAINT GREEN (450 825);
FORCEPROP 2 LAST CDS_LIB logical_power
J 0
(450 775);
DISPLAY INVISIBLE (450 775);
FORCEPROP 1 LAST PATH I33
J 0
(500 800);
DISPLAY 0.872340 (500 800);
PAINT AQUA (500 800);
DISPLAY INVISIBLE (500 800);
FORCEADD Q_RES..2
(700 -1300);
FORCEPROP 1 LAST PART_NUMBER CS31002BB06
J 0
(740 -1425);
DISPLAY 0.617021 (740 -1425);
PAINT BLUE (740 -1425);
DISPLAY INVISIBLE (740 -1425);
FORCEPROP 1 LAST WATTAGE 1/16W
J 0
(740 -1325);
DISPLAY 0.617021 (740 -1325);
PAINT SKYBLUE (740 -1325);
FORCEPROP 1 LAST VALUE 10K
J 0
(745 -1225);
DISPLAY 0.617021 (745 -1225);
PAINT SKYBLUE (745 -1225);
FORCEPROP 1 LAST PACK_TYPE 0402LF
J 0
(740 -1475);
DISPLAY 0.617021 (740 -1475);
PAINT SKYBLUE (740 -1475);
FORCEPROP 1 LAST MATERIAL CHIP
J 0
(740 -1375);
DISPLAY 0.617021 (740 -1375);
PAINT SKYBLUE (740 -1375);
FORCEPROP 1 LAST TOLERANCE 0.1%
J 0
(745 -1275);
DISPLAY 0.617021 (745 -1275);
PAINT SKYBLUE (745 -1275);
FORCEPROP 1 LAST LOCATION PR187
J 0
(745 -1175);
DISPLAY 0.617021 (745 -1175);
PAINT AQUA (745 -1175);
FORCEPROP 1 LASTPIN (700 -1200) $PN 1
J 0
(705 -1238);
DISPLAY 0.617021 (705 -1238);
FORCEPROP 1 LASTPIN (700 -1400) $PN 2
J 0
(705 -1390);
DISPLAY 0.617021 (705 -1390);
FORCEPROP 2 LAST CDS_LIB pure_quanta
J 0
(700 -1300);
DISPLAY INVISIBLE (700 -1300);
FORCEPROP 2 LAST BOM_COST VR_PCH
J 0
(750 -1125);
DISPLAY 0.680851 (750 -1125);
DISPLAY INVISIBLE (750 -1125);
FORCEPROP 1 LAST PATH I34
J 0
(750 -1125);
DISPLAY 0.978723 (750 -1125);
PAINT WHITE (750 -1125);
DISPLAY INVISIBLE (750 -1125);
FORCEPROP 2 LAST $SEC 1
J 0
(750 -1075);
DISPLAY 0.680851 (750 -1075);
PAINT MONO (750 -1075);
DISPLAY INVISIBLE (750 -1075);
FORCEPROP 2 LAST CDS_SEC 1
J 0
(750 -1075);
DISPLAY 0.680851 (750 -1075);
DISPLAY INVISIBLE (750 -1075);
FORCEADD Q_CAP..2
(1650 -1275);
FORCEPROP 1 LAST PART_NUMBER TMP_QCH16806KB17
J 1
(1475 -1350);
DISPLAY 0.617021 (1475 -1350);
PAINT BLUE (1475 -1350);
DISPLAY INVISIBLE (1475 -1350);
FORCEPROP 1 LAST VOLTAGE 50V
J 0
(1950 -1175);
DISPLAY 0.617021 (1950 -1175);
PAINT SKYBLUE (1950 -1175);
FORCEPROP 1 LAST PACK_TYPE 0402
J 1
(1825 -1175);
DISPLAY 0.617021 (1825 -1175);
PAINT SKYBLUE (1825 -1175);
FORCEPROP 1 LAST TOLERANCE 10%
J 2
(2075 -1275);
DISPLAY 0.617021 (2075 -1275);
PAINT SKYBLUE (2075 -1275);
FORCEPROP 1 LAST VALUE 680PF
J 2
(1925 -1275);
DISPLAY 0.617021 (1925 -1275);
PAINT SKYBLUE (1925 -1275);
FORCEPROP 1 LAST MATERIAL X7R
J 0
(1775 -1325);
DISPLAY 0.617021 (1775 -1325);
PAINT SKYBLUE (1775 -1325);
FORCEPROP 1 LAST LOCATION PC1223
J 1
(1400 -1275);
DISPLAY 0.617021 (1400 -1275);
PAINT AQUA (1400 -1275);
FORCEPROP 1 LASTPIN (1550 -1275) $PN 1
J 0
(1540 -1260);
DISPLAY 0.617021 (1540 -1260);
FORCEPROP 1 LASTPIN (1750 -1275) $PN 2
J 0
(1735 -1260);
DISPLAY 0.617021 (1735 -1260);
FORCEPROP 2 LAST CDS_LIB pure_quanta
J 0
(1650 -1275);
PAINT MONO (1650 -1275);
DISPLAY INVISIBLE (1650 -1275);
FORCEPROP 1 LAST PATH I35
J 0
(1650 -1075);
DISPLAY 0.978723 (1650 -1075);
PAINT WHITE (1650 -1075);
DISPLAY INVISIBLE (1650 -1075);
FORCEPROP 2 LAST $SEC 1
J 0
(1650 -1025);
DISPLAY 0.680851 (1650 -1025);
PAINT MONO (1650 -1025);
DISPLAY INVISIBLE (1650 -1025);
FORCEPROP 2 LAST CDS_SEC 1
J 0
(1650 -1025);
DISPLAY 1.021277 (1650 -1025);
DISPLAY INVISIBLE (1650 -1025);
FORCEADD Q_RES..1
(1650 -1050);
FORCEPROP 1 LAST PART_NUMBER CS27322BB09
J 0
(1250 -1100);
DISPLAY 0.617021 (1250 -1100);
PAINT BLUE (1250 -1100);
DISPLAY INVISIBLE (1250 -1100);
FORCEPROP 1 LAST MATERIAL CHIP
J 0
(1775 -1375);
DISPLAY 0.617021 (1775 -1375);
PAINT SKYBLUE (1775 -1375);
FORCEPROP 1 LAST TOLERANCE 0.1%
J 0
(1950 -1100);
DISPLAY 0.617021 (1950 -1100);
PAINT SKYBLUE (1950 -1100);
FORCEPROP 1 LAST VALUE 7.32K
J 2
(1900 -1100);
DISPLAY 0.617021 (1900 -1100);
PAINT SKYBLUE (1900 -1100);
FORCEPROP 1 LAST PACK_TYPE 0402LF
J 0
(1775 -1425);
DISPLAY 0.617021 (1775 -1425);
PAINT SKYBLUE (1775 -1425);
FORCEPROP 1 LAST WATTAGE 1/16W
J 2
(2125 -1325);
DISPLAY 0.617021 (2125 -1325);
PAINT SKYBLUE (2125 -1325);
FORCEPROP 1 LAST LOCATION PR1328
J 0
(1325 -1050);
DISPLAY 0.617021 (1325 -1050);
PAINT AQUA (1325 -1050);
FORCEPROP 1 LASTPIN (1550 -1050) $PN 1
J 0
(1562 -1038);
DISPLAY 0.617021 (1562 -1038);
PAINT MONO (1562 -1038);
FORCEPROP 1 LASTPIN (1750 -1050) $PN 2
J 0
(1712 -1038);
DISPLAY 0.617021 (1712 -1038);
PAINT MONO (1712 -1038);
FORCEPROP 2 LAST CDS_LIB pure_quanta
J 0
(1650 -1050);
DISPLAY INVISIBLE (1650 -1050);
FORCEPROP 1 LAST PATH I36
J 0
(1600 -900);
DISPLAY 0.978723 (1600 -900);
PAINT WHITE (1600 -900);
DISPLAY INVISIBLE (1600 -900);
FORCEPROP 2 LAST $SEC 1
J 0
(1600 -850);
DISPLAY 0.680851 (1600 -850);
PAINT MONO (1600 -850);
DISPLAY INVISIBLE (1600 -850);
FORCEPROP 2 LAST CDS_SEC 1
J 0
(1600 -850);
DISPLAY 1.021277 (1600 -850);
DISPLAY INVISIBLE (1600 -850);
FORCEADD Q_CAP..1
(2325 -1250);
FORCEPROP 1 LAST PART_NUMBER TMP_QCH31004KB17
J 0
(2375 -1400);
DISPLAY 0.617021 (2375 -1400);
PAINT BLUE (2375 -1400);
DISPLAY INVISIBLE (2375 -1400);
FORCEPROP 1 LAST TOLERANCE 10%
J 0
(2375 -1300);
DISPLAY 0.617021 (2375 -1300);
PAINT SKYBLUE (2375 -1300);
FORCEPROP 1 LAST PACK_TYPE 0402
J 0
(2375 -1450);
DISPLAY 0.617021 (2375 -1450);
PAINT SKYBLUE (2375 -1450);
FORCEPROP 1 LAST VOLTAGE 25V
J 0
(2375 -1250);
DISPLAY 0.617021 (2375 -1250);
PAINT SKYBLUE (2375 -1250);
FORCEPROP 1 LAST MATERIAL X7R
J 0
(2375 -1350);
DISPLAY 0.617021 (2375 -1350);
PAINT SKYBLUE (2375 -1350);
FORCEPROP 1 LAST VALUE 0.01UF
J 0
(2375 -1200);
DISPLAY 0.617021 (2375 -1200);
PAINT SKYBLUE (2375 -1200);
FORCEPROP 1 LAST LOCATION PC2279
J 0
(2375 -1150);
DISPLAY 0.617021 (2375 -1150);
PAINT AQUA (2375 -1150);
FORCEPROP 1 LASTPIN (2325 -1150) $PN 1
J 0
(2335 -1170);
DISPLAY 0.787234 (2335 -1170);
PAINT MONO (2335 -1170);
FORCEPROP 1 LASTPIN (2325 -1350) $PN 2
J 0
(2335 -1370);
DISPLAY 0.787234 (2335 -1370);
PAINT MONO (2335 -1370);
FORCEPROP 2 LAST CDS_LIB pure_quanta
J 0
(2325 -1250);
DISPLAY INVISIBLE (2325 -1250);
FORCEPROP 1 LAST PATH I37
J 0
(2375 -1100);
DISPLAY 0.978723 (2375 -1100);
PAINT WHITE (2375 -1100);
DISPLAY INVISIBLE (2375 -1100);
FORCEPROP 0 LAST $SEC 1
J 0
(2375 -1100);
DISPLAY 0.680851 (2375 -1100);
PAINT MONO (2375 -1100);
DISPLAY INVISIBLE (2375 -1100);
FORCEPROP 0 LAST CDS_SEC 1
J 0
(2375 -1100);
DISPLAY 1.021277 (2375 -1100);
DISPLAY INVISIBLE (2375 -1100);
FORCEADD Q_CAP..1
(2225 -550);
FORCEPROP 1 LAST PART_NUMBER CH4104K1B00
J 0
(2275 -700);
DISPLAY 0.617021 (2275 -700);
PAINT BLUE (2275 -700);
DISPLAY INVISIBLE (2275 -700);
FORCEPROP 1 LAST MATERIAL X7R
J 0
(2275 -650);
DISPLAY 0.617021 (2275 -650);
PAINT SKYBLUE (2275 -650);
FORCEPROP 1 LAST VOLTAGE 25V
J 0
(2275 -550);
DISPLAY 0.617021 (2275 -550);
PAINT SKYBLUE (2275 -550);
FORCEPROP 1 LAST VALUE 0.1UF
J 0
(2275 -500);
DISPLAY 0.617021 (2275 -500);
PAINT SKYBLUE (2275 -500);
FORCEPROP 1 LAST PACK_TYPE 0402
J 0
(2275 -750);
DISPLAY 0.617021 (2275 -750);
PAINT SKYBLUE (2275 -750);
FORCEPROP 1 LAST TOLERANCE 10%
J 0
(2275 -600);
DISPLAY 0.617021 (2275 -600);
PAINT SKYBLUE (2275 -600);
FORCEPROP 1 LAST LOCATION PC1224
J 0
(2275 -450);
DISPLAY 0.617021 (2275 -450);
PAINT AQUA (2275 -450);
FORCEPROP 1 LASTPIN (2225 -450) $PN 1
J 0
(2235 -470);
DISPLAY 0.617021 (2235 -470);
PAINT MONO (2235 -470);
FORCEPROP 1 LASTPIN (2225 -650) $PN 2
J 0
(2235 -670);
DISPLAY 0.617021 (2235 -670);
PAINT MONO (2235 -670);
FORCEPROP 2 LAST CDS_LIB pure_quanta
J 0
(2225 -550);
DISPLAY INVISIBLE (2225 -550);
FORCEPROP 1 LAST PATH I38
J 0
(2275 -400);
DISPLAY 0.978723 (2275 -400);
PAINT WHITE (2275 -400);
DISPLAY INVISIBLE (2275 -400);
FORCEPROP 2 LAST $SEC 1
J 0
(2275 -350);
DISPLAY 0.680851 (2275 -350);
PAINT MONO (2275 -350);
DISPLAY INVISIBLE (2275 -350);
FORCEPROP 2 LAST CDS_SEC 1
J 0
(2275 -350);
DISPLAY 1.021277 (2275 -350);
DISPLAY INVISIBLE (2275 -350);
FORCEADD UNIVERSAL_GND..1
(3675 -2850);
FORCEPROP 3 LASTPIN (3675 -2800) SIG_NAME GND\g
J 0
(3685 -2790);
DISPLAY 0.659574 (3685 -2790);
PAINT MONO (3685 -2790);
DISPLAY INVISIBLE (3685 -2790);
FORCEPROP 1 LAST HDL_POWER GND
J 1
(3700 -2925);
DISPLAY 0.872340 (3700 -2925);
PAINT GREEN (3700 -2925);
DISPLAY INVISIBLE (3700 -2925);
FORCEPROP 2 LAST CDS_LIB logical_power
J 0
(3675 -2850);
DISPLAY INVISIBLE (3675 -2850);
FORCEPROP 1 LAST PATH I39
J 0
(3750 -2850);
DISPLAY 0.872340 (3750 -2850);
PAINT AQUA (3750 -2850);
DISPLAY INVISIBLE (3750 -2850);
FORCEADD UNIVERSAL_POWER..1
(-3150 -775);
FORCEPROP 3 LASTPIN (-3150 -825) SIG_NAME P3V3_AUX\g
J 0
(-3140 -815);
DISPLAY 0.659574 (-3140 -815);
PAINT MONO (-3140 -815);
DISPLAY INVISIBLE (-3140 -815);
FORCEPROP 1 LAST HDL_POWER P3V3_AUX
J 1
(-3150 -725);
DISPLAY 0.617021 (-3150 -725);
PAINT GREEN (-3150 -725);
FORCEPROP 2 LAST CDS_LIB logical_power
J 0
(-3150 -775);
DISPLAY INVISIBLE (-3150 -775);
FORCEPROP 1 LAST PATH I4
J 0
(-3100 -750);
DISPLAY 0.872340 (-3100 -750);
PAINT AQUA (-3100 -750);
DISPLAY INVISIBLE (-3100 -750);
FORCEADD Q_CAPP..1
(2875 -2500);
FORCEPROP 1 LAST PART_NUMBER CH733RY8807
J 0
(2925 -2700);
DISPLAY 0.617021 (2925 -2700);
PAINT BLUE (2925 -2700);
DISPLAY INVISIBLE (2925 -2700);
FORCEPROP 1 LAST VOLTAGE 2V
J 0
(2925 -2550);
DISPLAY 0.617021 (2925 -2550);
PAINT SKYBLUE (2925 -2550);
FORCEPROP 1 LAST MATERIAL SPCAP
J 0
(2925 -2600);
DISPLAY 0.617021 (2925 -2600);
PAINT SKYBLUE (2925 -2600);
FORCEPROP 1 LAST PACK_TYPE SMLF
J 0
(2925 -2650);
DISPLAY 0.617021 (2925 -2650);
PAINT SKYBLUE (2925 -2650);
FORCEPROP 1 LAST TOLERANCE 35%
J 0
(2925 -2500);
DISPLAY 0.617021 (2925 -2500);
PAINT SKYBLUE (2925 -2500);
FORCEPROP 1 LAST VALUE 330UF
J 0
(2925 -2450);
DISPLAY 0.617021 (2925 -2450);
PAINT SKYBLUE (2925 -2450);
FORCEPROP 1 LAST LOCATION PC117
J 0
(2925 -2400);
DISPLAY 0.617021 (2925 -2400);
PAINT AQUA (2925 -2400);
FORCEPROP 1 LASTPIN (2875 -2400) $PN 1
J 0
(2885 -2415);
DISPLAY 0.787234 (2885 -2415);
PAINT MONO (2885 -2415);
FORCEPROP 1 LASTPIN (2875 -2600) $PN 2
J 0
(2885 -2615);
DISPLAY 0.787234 (2885 -2615);
PAINT MONO (2885 -2615);
FORCEPROP 2 LAST CDS_LIB pure_quanta
J 0
(2875 -2500);
DISPLAY INVISIBLE (2875 -2500);
FORCEPROP 1 LAST PATH I40
J 0
(2925 -2350);
DISPLAY 0.978723 (2925 -2350);
DISPLAY INVISIBLE (2925 -2350);
FORCEPROP 0 LAST $SEC 1
J 0
(2925 -2350);
DISPLAY 0.680851 (2925 -2350);
PAINT MONO (2925 -2350);
DISPLAY INVISIBLE (2925 -2350);
FORCEPROP 0 LAST CDS_SEC 1
J 0
(2925 -2350);
DISPLAY 1.021277 (2925 -2350);
DISPLAY INVISIBLE (2925 -2350);
FORCEADD Q_CAPP..1
(3275 -2500);
FORCEPROP 1 LAST PART_NUMBER CC7560JMD16
J 0
(3325 -2700);
DISPLAY 0.617021 (3325 -2700);
PAINT BLUE (3325 -2700);
DISPLAY INVISIBLE (3325 -2700);
FORCEPROP 1 LAST PACK_TYPE THLF
J 0
(3325 -2650);
DISPLAY 0.617021 (3325 -2650);
PAINT SKYBLUE (3325 -2650);
FORCEPROP 1 LAST VALUE 560UF
J 0
(3325 -2450);
DISPLAY 0.617021 (3325 -2450);
PAINT SKYBLUE (3325 -2450);
FORCEPROP 1 LAST TOLERANCE 20%
J 0
(3325 -2500);
DISPLAY 0.617021 (3325 -2500);
PAINT SKYBLUE (3325 -2500);
FORCEPROP 1 LAST VOLTAGE 2.5V
J 0
(3325 -2550);
DISPLAY 0.617021 (3325 -2550);
PAINT SKYBLUE (3325 -2550);
FORCEPROP 0 LAST OSCON OSCON
J 0
(3325 -2600);
DISPLAY 0.638298 (3325 -2600);
FORCEPROP 1 LAST LOCATION PC1227
J 0
(3325 -2400);
DISPLAY 0.617021 (3325 -2400);
PAINT AQUA (3325 -2400);
FORCEPROP 1 LASTPIN (3275 -2400) $PN 1
J 0
(3285 -2415);
DISPLAY 0.617021 (3285 -2415);
PAINT MONO (3285 -2415);
FORCEPROP 1 LASTPIN (3275 -2600) $PN 2
J 0
(3285 -2615);
DISPLAY 0.617021 (3285 -2615);
PAINT MONO (3285 -2615);
FORCEPROP 1 LAST MATERIAL OSCON
J 0
(3325 -2600);
DISPLAY 0.978723 (3325 -2600);
PAINT SKYBLUE (3325 -2600);
DISPLAY INVISIBLE (3325 -2600);
FORCEPROP 2 LAST BOM_COST VR_PCH
J 0
(3325 -2350);
DISPLAY 0.680851 (3325 -2350);
DISPLAY INVISIBLE (3325 -2350);
FORCEPROP 2 LAST CDS_LIB pure_quanta
J 0
(3275 -2500);
DISPLAY INVISIBLE (3275 -2500);
FORCEPROP 1 LAST PATH I41
J 0
(3325 -2350);
DISPLAY 0.978723 (3325 -2350);
DISPLAY INVISIBLE (3325 -2350);
FORCEPROP 2 LAST $SEC 1
J 0
(3325 -2300);
DISPLAY 0.680851 (3325 -2300);
PAINT MONO (3325 -2300);
DISPLAY INVISIBLE (3325 -2300);
FORCEPROP 2 LAST CDS_SEC 1
J 0
(3325 -2300);
DISPLAY 1.021277 (3325 -2300);
DISPLAY INVISIBLE (3325 -2300);
FORCEADD Q_SHORT..1
(3000 -1525);
FORCEPROP 1 LAST PART_NUMBER SHORT6
J 0
(2925 -1415);
DISPLAY 0.617021 (2925 -1415);
PAINT BLUE (2925 -1415);
DISPLAY INVISIBLE (2925 -1415);
FORCEPROP 2 LAST PACK_TYPE SM
J 0
(2925 -1325);
DISPLAY 0.617021 (2925 -1325);
PAINT SKYBLUE (2925 -1325);
FORCEPROP 1 LAST MATERIAL EMPTY
J 0
(2925 -1365);
DISPLAY 0.617021 (2925 -1365);
PAINT RED (2925 -1365);
FORCEPROP 1 LAST LOCATION PJ63
J 0
(2925 -1470);
DISPLAY 0.617021 (2925 -1470);
PAINT AQUA (2925 -1470);
FORCEPROP 0 LASTPIN (2875 -1525) $PN 1
J 2
(2865 -1515);
DISPLAY 0.808511 (2865 -1515);
FORCEPROP 0 LASTPIN (3125 -1525) $PN 2
J 0
(3135 -1515);
DISPLAY 0.808511 (3135 -1515);
FORCEPROP 2 LAST CDS_LIB pure_quanta
J 0
(3000 -1525);
DISPLAY INVISIBLE (3000 -1525);
FORCEPROP 2 LAST BOM_COST VR_PCH
J 0
(2925 -1275);
DISPLAY 0.680851 (2925 -1275);
DISPLAY INVISIBLE (2925 -1275);
FORCEPROP 1 LAST NEEDS_NO_SIZE TRUE
J 0
(3000 -1525);
DISPLAY 0.468085 (3000 -1525);
PAINT GREEN (3000 -1525);
DISPLAY INVISIBLE (3000 -1525);
FORCEPROP 1 LAST PATH I42
J 0
(2925 -1320);
DISPLAY 0.723404 (2925 -1320);
PAINT GREEN (2925 -1320);
DISPLAY INVISIBLE (2925 -1320);
FORCEPROP 0 LAST $SEC 1
J 0
(2925 -1275);
DISPLAY INVISIBLE (2925 -1275);
FORCEPROP 0 LAST CDS_SEC 1
J 0
(2925 -1275);
DISPLAY INVISIBLE (2925 -1275);
FORCEADD Q_SHORT..1
(3000 -1050);
FORCEPROP 1 LAST PART_NUMBER SHORT6
J 0
(2925 -940);
DISPLAY 0.617021 (2925 -940);
PAINT BLUE (2925 -940);
DISPLAY INVISIBLE (2925 -940);
FORCEPROP 1 LAST MATERIAL EMPTY
J 0
(2925 -890);
DISPLAY 0.617021 (2925 -890);
PAINT RED (2925 -890);
FORCEPROP 2 LAST PACK_TYPE SM
J 0
(2925 -850);
DISPLAY 0.617021 (2925 -850);
PAINT SKYBLUE (2925 -850);
FORCEPROP 1 LAST LOCATION PJ62
J 0
(2925 -995);
DISPLAY 0.617021 (2925 -995);
PAINT AQUA (2925 -995);
FORCEPROP 2 LASTPIN (2875 -1050) $PN 1
J 2
(2865 -1040);
DISPLAY 0.617021 (2865 -1040);
FORCEPROP 2 LASTPIN (3125 -1050) $PN 2
J 0
(3135 -1040);
DISPLAY 0.617021 (3135 -1040);
FORCEPROP 2 LAST BOM_COST VR_PCH
J 0
(2925 -800);
DISPLAY 0.680851 (2925 -800);
DISPLAY INVISIBLE (2925 -800);
FORCEPROP 1 LAST NEEDS_NO_SIZE TRUE
J 0
(3000 -1050);
DISPLAY 0.468085 (3000 -1050);
PAINT GREEN (3000 -1050);
DISPLAY INVISIBLE (3000 -1050);
FORCEPROP 2 LAST CDS_LIB pure_quanta
J 0
(3000 -1050);
DISPLAY INVISIBLE (3000 -1050);
FORCEPROP 1 LAST PATH I43
J 0
(2925 -845);
DISPLAY 0.723404 (2925 -845);
PAINT GREEN (2925 -845);
DISPLAY INVISIBLE (2925 -845);
FORCEPROP 2 LAST $SEC 1
J 0
(2925 -800);
DISPLAY 0.680851 (2925 -800);
PAINT MONO (2925 -800);
DISPLAY INVISIBLE (2925 -800);
FORCEPROP 2 LAST CDS_SEC 1
J 0
(2925 -800);
DISPLAY 1.021277 (2925 -800);
DISPLAY INVISIBLE (2925 -800);
FORCEADD Q_CAP..1
(2650 -550);
FORCEPROP 1 LAST PART_NUMBER CH647KMEA04
J 0
(2700 -700);
DISPLAY 0.617021 (2700 -700);
PAINT BLUE (2700 -700);
DISPLAY INVISIBLE (2700 -700);
FORCEPROP 1 LAST TOLERANCE 20%
J 0
(2700 -600);
DISPLAY 0.617021 (2700 -600);
PAINT SKYBLUE (2700 -600);
FORCEPROP 1 LAST PACK_TYPE C0805
J 0
(2700 -750);
DISPLAY 0.617021 (2700 -750);
PAINT SKYBLUE (2700 -750);
FORCEPROP 1 LAST VOLTAGE 4V
J 0
(2700 -550);
DISPLAY 0.617021 (2700 -550);
PAINT SKYBLUE (2700 -550);
FORCEPROP 1 LAST VALUE 47UF
J 0
(2700 -500);
DISPLAY 0.617021 (2700 -500);
PAINT SKYBLUE (2700 -500);
FORCEPROP 1 LAST MATERIAL X6S
J 0
(2700 -650);
DISPLAY 0.617021 (2700 -650);
PAINT SKYBLUE (2700 -650);
FORCEPROP 1 LAST LOCATION PC1225
J 0
(2700 -450);
DISPLAY 0.617021 (2700 -450);
PAINT AQUA (2700 -450);
FORCEPROP 1 LASTPIN (2650 -450) $PN 1
J 0
(2660 -470);
DISPLAY 0.617021 (2660 -470);
PAINT MONO (2660 -470);
FORCEPROP 1 LASTPIN (2650 -650) $PN 2
J 0
(2660 -670);
DISPLAY 0.617021 (2660 -670);
PAINT MONO (2660 -670);
FORCEPROP 2 LAST CDS_LIB pure_quanta
J 0
(2650 -550);
DISPLAY INVISIBLE (2650 -550);
FORCEPROP 2 LAST BOM_COST VR_PCH
J 0
(2700 -400);
DISPLAY 0.680851 (2700 -400);
DISPLAY INVISIBLE (2700 -400);
FORCEPROP 1 LAST PATH I44
J 0
(2700 -400);
DISPLAY 0.978723 (2700 -400);
PAINT WHITE (2700 -400);
DISPLAY INVISIBLE (2700 -400);
FORCEPROP 2 LAST $SEC 1
J 0
(2700 -350);
DISPLAY 0.680851 (2700 -350);
PAINT MONO (2700 -350);
DISPLAY INVISIBLE (2700 -350);
FORCEPROP 2 LAST CDS_SEC 1
J 0
(2700 -350);
DISPLAY 1.021277 (2700 -350);
DISPLAY INVISIBLE (2700 -350);
FORCEADD Q_CAP..1
(3025 -550);
FORCEPROP 1 LAST PART_NUMBER CH647KMEA04
J 0
(3075 -700);
DISPLAY 0.617021 (3075 -700);
PAINT BLUE (3075 -700);
DISPLAY INVISIBLE (3075 -700);
FORCEPROP 1 LAST TOLERANCE 20%
J 0
(3075 -600);
DISPLAY 0.617021 (3075 -600);
PAINT SKYBLUE (3075 -600);
FORCEPROP 1 LAST PACK_TYPE C0805
J 0
(3075 -750);
DISPLAY 0.617021 (3075 -750);
PAINT SKYBLUE (3075 -750);
FORCEPROP 1 LAST VOLTAGE 4V
J 0
(3075 -550);
DISPLAY 0.617021 (3075 -550);
PAINT SKYBLUE (3075 -550);
FORCEPROP 1 LAST VALUE 47UF
J 0
(3075 -500);
DISPLAY 0.617021 (3075 -500);
PAINT SKYBLUE (3075 -500);
FORCEPROP 1 LAST MATERIAL X6S
J 0
(3075 -650);
DISPLAY 0.617021 (3075 -650);
PAINT SKYBLUE (3075 -650);
FORCEPROP 1 LAST LOCATION PC1226
J 0
(3075 -450);
DISPLAY 0.617021 (3075 -450);
PAINT AQUA (3075 -450);
FORCEPROP 1 LASTPIN (3025 -450) $PN 1
J 0
(3035 -470);
DISPLAY 0.617021 (3035 -470);
PAINT MONO (3035 -470);
FORCEPROP 1 LASTPIN (3025 -650) $PN 2
J 0
(3035 -670);
DISPLAY 0.617021 (3035 -670);
PAINT MONO (3035 -670);
FORCEPROP 2 LAST CDS_LIB pure_quanta
J 0
(3025 -550);
DISPLAY INVISIBLE (3025 -550);
FORCEPROP 2 LAST BOM_COST VR_PCH
J 0
(3075 -400);
DISPLAY 0.680851 (3075 -400);
DISPLAY INVISIBLE (3075 -400);
FORCEPROP 1 LAST PATH I45
J 0
(3075 -400);
DISPLAY 0.978723 (3075 -400);
PAINT WHITE (3075 -400);
DISPLAY INVISIBLE (3075 -400);
FORCEPROP 2 LAST $SEC 1
J 0
(3075 -350);
DISPLAY 0.680851 (3075 -350);
PAINT MONO (3075 -350);
DISPLAY INVISIBLE (3075 -350);
FORCEPROP 2 LAST CDS_SEC 1
J 0
(3075 -350);
DISPLAY 1.021277 (3075 -350);
DISPLAY INVISIBLE (3075 -350);
FORCEADD UNIVERSAL_GND..1
(3450 -875);
FORCEPROP 3 LASTPIN (3450 -825) SIG_NAME GND\g
J 0
(3460 -815);
DISPLAY 0.659574 (3460 -815);
PAINT MONO (3460 -815);
DISPLAY INVISIBLE (3460 -815);
FORCEPROP 1 LAST HDL_POWER GND
J 1
(3475 -950);
DISPLAY 0.872340 (3475 -950);
PAINT GREEN (3475 -950);
DISPLAY INVISIBLE (3475 -950);
FORCEPROP 2 LAST CDS_LIB logical_power
J 0
(3450 -875);
DISPLAY INVISIBLE (3450 -875);
FORCEPROP 1 LAST PATH I46
J 0
(3525 -875);
DISPLAY 0.872340 (3525 -875);
PAINT AQUA (3525 -875);
DISPLAY INVISIBLE (3525 -875);
FORCEADD Q_CAPP..1
(3450 -550);
FORCEPROP 1 LAST PART_NUMBER CH733RY8807
J 0
(3500 -700);
DISPLAY 0.617021 (3500 -700);
PAINT BLUE (3500 -700);
DISPLAY INVISIBLE (3500 -700);
FORCEPROP 1 LAST PACK_TYPE SMLF
J 0
(3500 -750);
DISPLAY 0.617021 (3500 -750);
PAINT SKYBLUE (3500 -750);
FORCEPROP 1 LAST TOLERANCE 35%
J 0
(3500 -550);
DISPLAY 0.617021 (3500 -550);
PAINT SKYBLUE (3500 -550);
FORCEPROP 1 LAST VOLTAGE 2V
J 0
(3500 -600);
DISPLAY 0.617021 (3500 -600);
PAINT SKYBLUE (3500 -600);
FORCEPROP 1 LAST VALUE 330UF
J 0
(3500 -500);
DISPLAY 0.617021 (3500 -500);
PAINT SKYBLUE (3500 -500);
FORCEPROP 1 LAST MATERIAL SPCAP
J 0
(3500 -650);
DISPLAY 0.617021 (3500 -650);
PAINT RED (3500 -650);
FORCEPROP 1 LAST LOCATION PC1229
J 0
(3500 -450);
DISPLAY 0.617021 (3500 -450);
PAINT AQUA (3500 -450);
FORCEPROP 1 LASTPIN (3450 -450) $PN 1
J 0
(3460 -465);
DISPLAY 0.617021 (3460 -465);
PAINT MONO (3460 -465);
FORCEPROP 1 LASTPIN (3450 -650) $PN 2
J 0
(3460 -665);
DISPLAY 0.617021 (3460 -665);
PAINT MONO (3460 -665);
FORCEPROP 2 LAST CDS_LIB pure_quanta
J 0
(3450 -550);
DISPLAY INVISIBLE (3450 -550);
FORCEPROP 2 LAST BOM_COST VR_PCH
J 0
(3500 -400);
DISPLAY 0.680851 (3500 -400);
DISPLAY INVISIBLE (3500 -400);
FORCEPROP 1 LAST PATH I47
J 0
(3500 -400);
DISPLAY 0.978723 (3500 -400);
DISPLAY INVISIBLE (3500 -400);
FORCEPROP 2 LAST $SEC 1
J 0
(3500 -350);
DISPLAY 0.680851 (3500 -350);
PAINT MONO (3500 -350);
DISPLAY INVISIBLE (3500 -350);
FORCEPROP 2 LAST CDS_SEC 1
J 0
(3500 -350);
DISPLAY 1.021277 (3500 -350);
DISPLAY INVISIBLE (3500 -350);
FORCEADD Q_CAPP..1
(3675 -2500);
FORCEPROP 1 LAST PART_NUMBER CC7560JMD16
J 0
(3725 -2700);
DISPLAY 0.617021 (3725 -2700);
PAINT BLUE (3725 -2700);
DISPLAY INVISIBLE (3725 -2700);
FORCEPROP 1 LAST PACK_TYPE THLF
J 0
(3725 -2650);
DISPLAY 0.617021 (3725 -2650);
PAINT SKYBLUE (3725 -2650);
FORCEPROP 1 LAST VALUE 560UF
J 0
(3725 -2450);
DISPLAY 0.617021 (3725 -2450);
PAINT SKYBLUE (3725 -2450);
FORCEPROP 1 LAST TOLERANCE 20%
J 0
(3725 -2500);
DISPLAY 0.617021 (3725 -2500);
PAINT SKYBLUE (3725 -2500);
FORCEPROP 1 LAST VOLTAGE 2.5V
J 0
(3725 -2550);
DISPLAY 0.617021 (3725 -2550);
PAINT SKYBLUE (3725 -2550);
FORCEPROP 0 LAST OSCON OSCON
J 0
(3725 -2600);
DISPLAY 0.638298 (3725 -2600);
FORCEPROP 1 LAST LOCATION PC1230
J 0
(3725 -2400);
DISPLAY 0.617021 (3725 -2400);
PAINT AQUA (3725 -2400);
FORCEPROP 1 LASTPIN (3675 -2400) $PN 1
J 0
(3685 -2415);
DISPLAY 0.617021 (3685 -2415);
PAINT MONO (3685 -2415);
FORCEPROP 1 LASTPIN (3675 -2600) $PN 2
J 0
(3685 -2615);
DISPLAY 0.617021 (3685 -2615);
PAINT MONO (3685 -2615);
FORCEPROP 1 LAST MATERIAL OSCON
J 0
(3725 -2600);
DISPLAY 0.978723 (3725 -2600);
PAINT SKYBLUE (3725 -2600);
DISPLAY INVISIBLE (3725 -2600);
FORCEPROP 2 LAST BOM_COST VR_PCH
J 0
(3725 -2350);
DISPLAY 0.680851 (3725 -2350);
DISPLAY INVISIBLE (3725 -2350);
FORCEPROP 2 LAST CDS_LIB pure_quanta
J 0
(3675 -2500);
DISPLAY INVISIBLE (3675 -2500);
FORCEPROP 1 LAST PATH I48
J 0
(3725 -2350);
DISPLAY 0.978723 (3725 -2350);
DISPLAY INVISIBLE (3725 -2350);
FORCEPROP 2 LAST $SEC 1
J 0
(3725 -2300);
DISPLAY 0.680851 (3725 -2300);
PAINT MONO (3725 -2300);
DISPLAY INVISIBLE (3725 -2300);
FORCEPROP 2 LAST CDS_SEC 1
J 0
(3725 -2300);
DISPLAY 1.021277 (3725 -2300);
DISPLAY INVISIBLE (3725 -2300);
FORCEADD VCCAUX15..1
(3675 -2200);
FORCEPROP 3 LASTPIN (3675 -2250) SIG_NAME P1V05_PCH_AUX\g
J 0
(3685 -2240);
DISPLAY 0.659574 (3685 -2240);
PAINT MONO (3685 -2240);
DISPLAY INVISIBLE (3685 -2240);
FORCEPROP 1 LAST HDL_POWER P1V05_PCH_AUX
J 1
(3675 -2150);
DISPLAY 0.617021 (3675 -2150);
PAINT GREEN (3675 -2150);
FORCEPROP 2 LAST BOM_COST VR_PCH
J 0
(3675 -2100);
DISPLAY 0.680851 (3675 -2100);
DISPLAY INVISIBLE (3675 -2100);
FORCEPROP 2 LAST CDS_LIB logical_power
J 0
(3675 -2200);
DISPLAY INVISIBLE (3675 -2200);
FORCEPROP 1 LAST PATH I49
J 0
(3725 -2175);
DISPLAY 0.872340 (3725 -2175);
PAINT AQUA (3725 -2175);
DISPLAY INVISIBLE (3725 -2175);
FORCEADD UNIVERSAL_GND..1
(-2100 -1700);
FORCEPROP 3 LASTPIN (-2100 -1650) SIG_NAME GND\g
J 0
(-2090 -1640);
DISPLAY 0.659574 (-2090 -1640);
PAINT MONO (-2090 -1640);
DISPLAY INVISIBLE (-2090 -1640);
FORCEPROP 1 LAST HDL_POWER GND
J 1
(-2075 -1775);
DISPLAY 0.872340 (-2075 -1775);
PAINT GREEN (-2075 -1775);
DISPLAY INVISIBLE (-2075 -1775);
FORCEPROP 2 LAST CDS_LIB logical_power
J 0
(-2100 -1700);
DISPLAY INVISIBLE (-2100 -1700);
FORCEPROP 1 LAST PATH I5
J 0
(-2025 -1700);
DISPLAY 0.872340 (-2025 -1700);
PAINT AQUA (-2025 -1700);
DISPLAY INVISIBLE (-2025 -1700);
FORCEADD UNIVERSAL_GND..1
(3825 -1825);
FORCEPROP 3 LASTPIN (3825 -1775) SIG_NAME GND\g
J 0
(3835 -1765);
DISPLAY 0.659574 (3835 -1765);
PAINT MONO (3835 -1765);
DISPLAY INVISIBLE (3835 -1765);
FORCEPROP 1 LAST HDL_POWER GND
J 1
(3850 -1900);
DISPLAY 0.872340 (3850 -1900);
PAINT GREEN (3850 -1900);
DISPLAY INVISIBLE (3850 -1900);
FORCEPROP 2 LAST CDS_LIB logical_power
J 0
(3825 -1825);
DISPLAY INVISIBLE (3825 -1825);
FORCEPROP 1 LAST PATH I50
J 0
(3900 -1825);
DISPLAY 0.872340 (3900 -1825);
PAINT AQUA (3900 -1825);
DISPLAY INVISIBLE (3900 -1825);
FORCEADD Q_RES..1
(975 150);
FORCEPROP 1 LAST PART_NUMBER CS00002JB13
J 0
(925 200);
DISPLAY 0.404255 (925 200);
PAINT BLUE (925 200);
DISPLAY INVISIBLE (925 200);
FORCEPROP 1 LAST MATERIAL CHIP
J 0
(1225 150);
DISPLAY 0.617021 (1225 150);
PAINT SKYBLUE (1225 150);
FORCEPROP 1 LAST TOLERANCE 5%
J 0
(1150 150);
DISPLAY 0.617021 (1150 150);
PAINT SKYBLUE (1150 150);
FORCEPROP 1 LAST VALUE 0
J 2
(1125 150);
DISPLAY 0.617021 (1125 150);
PAINT SKYBLUE (1125 150);
FORCEPROP 1 LAST LOCATION R1650
J 0
(725 150);
DISPLAY 0.617021 (725 150);
PAINT AQUA (725 150);
FORCEPROP 1 LASTPIN (875 150) $PN 1
J 0
(887 162);
DISPLAY 0.617021 (887 162);
FORCEPROP 1 LASTPIN (1075 150) $PN 2
J 0
(1037 162);
DISPLAY 0.617021 (1037 162);
FORCEPROP 2 LAST CDS_LIB pure_quanta
J 0
(975 150);
PAINT MONO (975 150);
DISPLAY INVISIBLE (975 150);
FORCEPROP 1 LAST WATTAGE 1/16W
J 2
(1150 225);
DISPLAY 0.404255 (1150 225);
PAINT SKYBLUE (1150 225);
DISPLAY INVISIBLE (1150 225);
FORCEPROP 1 LAST PACK_TYPE 0402LF
J 0
(925 250);
DISPLAY 0.404255 (925 250);
PAINT SKYBLUE (925 250);
DISPLAY INVISIBLE (925 250);
FORCEPROP 1 LAST PATH I51
J 0
(925 300);
DISPLAY 0.978723 (925 300);
PAINT WHITE (925 300);
DISPLAY INVISIBLE (925 300);
FORCEPROP 2 LAST $SEC 1
J 0
(925 350);
DISPLAY 0.680851 (925 350);
PAINT MONO (925 350);
DISPLAY INVISIBLE (925 350);
FORCEPROP 2 LAST CDS_SEC 1
J 0
(925 350);
DISPLAY 1.021277 (925 350);
DISPLAY INVISIBLE (925 350);
FORCEADD Q_RES..1
(975 275);
FORCEPROP 1 LAST PART_NUMBER CS00002JB13
J 0
(925 325);
DISPLAY 0.617021 (925 325);
PAINT BLUE (925 325);
DISPLAY INVISIBLE (925 325);
FORCEPROP 1 LAST TOLERANCE 5%
J 0
(1150 275);
DISPLAY 0.617021 (1150 275);
PAINT SKYBLUE (1150 275);
FORCEPROP 1 LAST VALUE 0
J 2
(1125 275);
DISPLAY 0.617021 (1125 275);
PAINT SKYBLUE (1125 275);
FORCEPROP 1 LAST WATTAGE 1/16W
J 2
(1150 350);
DISPLAY 0.617021 (1150 350);
PAINT SKYBLUE (1150 350);
FORCEPROP 1 LAST MATERIAL CHIP
J 0
(1225 275);
DISPLAY 0.617021 (1225 275);
PAINT SKYBLUE (1225 275);
FORCEPROP 1 LAST PACK_TYPE 0402LF
J 0
(925 350);
DISPLAY 0.617021 (925 350);
PAINT SKYBLUE (925 350);
FORCEPROP 1 LAST LOCATION R4780
J 0
(725 275);
DISPLAY 0.617021 (725 275);
PAINT AQUA (725 275);
FORCEPROP 1 LASTPIN (875 275) $PN 1
J 0
(887 287);
DISPLAY 0.617021 (887 287);
FORCEPROP 1 LASTPIN (1075 275) $PN 2
J 0
(1037 287);
DISPLAY 0.617021 (1037 287);
FORCEPROP 2 LAST CDS_LIB pure_quanta
J 0
(975 275);
PAINT MONO (975 275);
DISPLAY INVISIBLE (975 275);
FORCEPROP 1 LAST PATH I52
J 0
(925 425);
DISPLAY 0.978723 (925 425);
PAINT WHITE (925 425);
DISPLAY INVISIBLE (925 425);
FORCEPROP 2 LAST $SEC 1
J 0
(925 475);
DISPLAY 0.680851 (925 475);
PAINT MONO (925 475);
DISPLAY INVISIBLE (925 475);
FORCEPROP 2 LAST CDS_SEC 1
J 0
(925 475);
DISPLAY 1.021277 (925 475);
DISPLAY INVISIBLE (925 475);
FORCEADD Q_INDUCTOR..1
(1375 -325);
FORCEPROP 1 LAST PART_NUMBER CV+30Y0KZ05
J 0
(1250 -215);
DISPLAY 0.617021 (1250 -215);
PAINT BLUE (1250 -215);
DISPLAY INVISIBLE (1250 -215);
FORCEPROP 1 LAST MATERIAL IND
J 0
(1250 -270);
DISPLAY 0.617021 (1250 -270);
PAINT SKYBLUE (1250 -270);
FORCEPROP 2 LAST VALUE 300NH/33A
J 0
(1250 -150);
DISPLAY 0.617021 (1250 -150);
PAINT SKYBLUE (1250 -150);
FORCEPROP 2 LAST PACK_TYPE SMLF
J 0
(1250 -100);
DISPLAY 0.617021 (1250 -100);
PAINT SKYBLUE (1250 -100);
FORCEPROP 1 LAST LOCATION PL150
J 0
(1075 -340);
DISPLAY 0.617021 (1075 -340);
PAINT AQUA (1075 -340);
FORCEPROP 2 LASTPIN (1275 -350) $PN 1
J 2
(1265 -340);
DISPLAY 0.617021 (1265 -340);
FORCEPROP 2 LASTPIN (1475 -350) $PN 2
J 0
(1485 -340);
DISPLAY 0.617021 (1485 -340);
FORCEPROP 2 LAST CDS_LIB pure_quanta
J 0
(1375 -325);
PAINT MONO (1375 -325);
DISPLAY INVISIBLE (1375 -325);
FORCEPROP 1 LAST NEEDS_NO_SIZE TRUE
J 0
(1375 -325);
DISPLAY 0.468085 (1375 -325);
PAINT GREEN (1375 -325);
DISPLAY INVISIBLE (1375 -325);
FORCEPROP 2 LAST BOM_COST VR_PCH
J 0
(1250 -25);
DISPLAY 0.680851 (1250 -25);
DISPLAY INVISIBLE (1250 -25);
FORCEPROP 1 LAST PATH I53
J 0
(1450 -270);
DISPLAY 0.723404 (1450 -270);
PAINT GREEN (1450 -270);
DISPLAY INVISIBLE (1450 -270);
FORCEPROP 2 LAST $SEC 1
J 0
(1250 -50);
DISPLAY 0.680851 (1250 -50);
PAINT MONO (1250 -50);
DISPLAY INVISIBLE (1250 -50);
FORCEPROP 2 LAST CDS_SEC 1
J 0
(1250 -50);
DISPLAY 1.021277 (1250 -50);
DISPLAY INVISIBLE (1250 -50);
FORCEADD OFFPAGE..2
(2375 275);
FORCEPROP 2 LAST $XR0 213 
J 0
(2564 275);
DISPLAY 0.638298 (2564 275);
PAINT MONO (2564 275);
FORCEPROP 1 LAST COMMENT_BODY TRUE
J 0
(2330 180);
DISPLAY 0.531915 (2330 180);
PAINT GREEN (2330 180);
DISPLAY INVISIBLE (2330 180);
FORCEPROP 1 LAST OFFPAGE TRUE
J 0
(2700 150);
DISPLAY 0.531915 (2700 150);
PAINT GREEN (2700 150);
DISPLAY INVISIBLE (2700 150);
FORCEPROP 2 LAST BOM_COST VR_SYSTEM 
J 0
(2725 325);
DISPLAY 0.680851 (2725 325);
DISPLAY INVISIBLE (2725 325);
FORCEPROP 2 LAST CDS_LIB standard
J 0
(2375 275);
PAINT MONO (2375 275);
DISPLAY INVISIBLE (2375 275);
FORCEPROP 2 LAST PATH I54
J 0
(2575 325);
DISPLAY 1.021277 (2575 325);
DISPLAY INVISIBLE (2575 325);
FORCEADD OFFPAGE..2
(2375 150);
FORCEPROP 2 LAST $XR1 252 
J 0
(2684 150);
DISPLAY 0.638298 (2684 150);
PAINT MONO (2684 150);
FORCEPROP 2 LAST $XR0 214 
J 0
(2564 150);
DISPLAY 0.638298 (2564 150);
PAINT MONO (2564 150);
FORCEPROP 1 LAST COMMENT_BODY TRUE
J 0
(2330 55);
DISPLAY 0.531915 (2330 55);
PAINT GREEN (2330 55);
DISPLAY INVISIBLE (2330 55);
FORCEPROP 1 LAST OFFPAGE TRUE
J 0
(2700 25);
DISPLAY 0.531915 (2700 25);
PAINT GREEN (2700 25);
DISPLAY INVISIBLE (2700 25);
FORCEPROP 2 LAST CDS_LIB standard
J 0
(2375 150);
PAINT MONO (2375 150);
DISPLAY INVISIBLE (2375 150);
FORCEPROP 2 LAST BOM_COST VR_SYSTEM 
J 0
(2725 200);
DISPLAY 0.680851 (2725 200);
DISPLAY INVISIBLE (2725 200);
FORCEPROP 2 LAST PATH I55
J 0
(2700 200);
DISPLAY 1.021277 (2700 200);
DISPLAY INVISIBLE (2700 200);
FORCEADD UNIVERSAL_POWER..1
(3825 -125);
FORCEPROP 3 LASTPIN (3825 -175) SIG_NAME P1V05_PCH_AUX\g
J 0
(3835 -165);
DISPLAY 0.659574 (3835 -165);
PAINT MONO (3835 -165);
DISPLAY INVISIBLE (3835 -165);
FORCEPROP 1 LAST HDL_POWER P1V05_PCH_AUX
J 1
(3825 -75);
DISPLAY 0.617021 (3825 -75);
PAINT GREEN (3825 -75);
FORCEPROP 2 LAST CDS_LIB logical_power
J 0
(3825 -125);
DISPLAY INVISIBLE (3825 -125);
FORCEPROP 1 LAST PATH I56
J 0
(3875 -100);
DISPLAY 0.872340 (3875 -100);
PAINT AQUA (3875 -100);
DISPLAY INVISIBLE (3875 -100);
FORCEADD Q_RES..2
(-2100 -1450);
FORCEPROP 1 LAST PART_NUMBER CS28452FB06
J 0
(-2060 -1575);
DISPLAY 0.617021 (-2060 -1575);
PAINT BLUE (-2060 -1575);
DISPLAY INVISIBLE (-2060 -1575);
FORCEPROP 1 LAST PACK_TYPE 0402LF
J 0
(-2060 -1625);
DISPLAY 0.617021 (-2060 -1625);
PAINT SKYBLUE (-2060 -1625);
FORCEPROP 1 LAST MATERIAL CHIP
J 0
(-2060 -1525);
DISPLAY 0.617021 (-2060 -1525);
PAINT SKYBLUE (-2060 -1525);
FORCEPROP 1 LAST WATTAGE 1/16W
J 0
(-2060 -1475);
DISPLAY 0.617021 (-2060 -1475);
PAINT SKYBLUE (-2060 -1475);
FORCEPROP 1 LAST TOLERANCE 1%
J 0
(-2055 -1425);
DISPLAY 0.617021 (-2055 -1425);
PAINT SKYBLUE (-2055 -1425);
FORCEPROP 1 LAST VALUE 8.45K
J 0
(-2055 -1375);
DISPLAY 0.617021 (-2055 -1375);
PAINT SKYBLUE (-2055 -1375);
FORCEPROP 1 LAST LOCATION PR1327
J 0
(-2055 -1325);
DISPLAY 0.617021 (-2055 -1325);
PAINT AQUA (-2055 -1325);
FORCEPROP 1 LASTPIN (-2100 -1350) $PN 1
J 0
(-2095 -1388);
DISPLAY 0.617021 (-2095 -1388);
FORCEPROP 1 LASTPIN (-2100 -1550) $PN 2
J 0
(-2095 -1540);
DISPLAY 0.617021 (-2095 -1540);
FORCEPROP 2 LAST CDS_LIB pure_quanta
J 0
(-2100 -1450);
PAINT MONO (-2100 -1450);
DISPLAY INVISIBLE (-2100 -1450);
FORCEPROP 1 LAST PATH I6
J 0
(-2050 -1275);
DISPLAY 0.978723 (-2050 -1275);
PAINT WHITE (-2050 -1275);
DISPLAY INVISIBLE (-2050 -1275);
FORCEPROP 2 LAST $SEC 1
J 0
(-2050 -1225);
DISPLAY 0.680851 (-2050 -1225);
PAINT MONO (-2050 -1225);
DISPLAY INVISIBLE (-2050 -1225);
FORCEPROP 2 LAST CDS_SEC 1
J 0
(-2050 -1225);
DISPLAY 1.021277 (-2050 -1225);
DISPLAY INVISIBLE (-2050 -1225);
FORCEADD UNIVERSAL_GND..1
(-2350 -900);
FORCEPROP 3 LASTPIN (-2350 -850) SIG_NAME GND\g
J 0
(-2340 -840);
DISPLAY 0.659574 (-2340 -840);
PAINT MONO (-2340 -840);
DISPLAY INVISIBLE (-2340 -840);
FORCEPROP 1 LAST HDL_POWER GND
J 1
(-2325 -975);
DISPLAY 0.872340 (-2325 -975);
PAINT GREEN (-2325 -975);
DISPLAY INVISIBLE (-2325 -975);
FORCEPROP 2 LAST CDS_LIB logical_power
J 0
(-2350 -900);
PAINT MONO (-2350 -900);
DISPLAY INVISIBLE (-2350 -900);
FORCEPROP 1 LAST PATH I7
J 0
(-2275 -900);
DISPLAY 0.872340 (-2275 -900);
PAINT AQUA (-2275 -900);
DISPLAY INVISIBLE (-2275 -900);
FORCEADD Q_CAP..1
R 2
(-2450 -575);
FORCEPROP 1 LAST PART_NUMBER TMP_QCH21006JB10
J 2
(-2500 -700);
DISPLAY 0.617021 (-2500 -700);
PAINT BLUE (-2500 -700);
DISPLAY INVISIBLE (-2500 -700);
FORCEPROP 1 LAST TOLERANCE 5%
J 2
(-2500 -600);
DISPLAY 0.617021 (-2500 -600);
PAINT SKYBLUE (-2500 -600);
FORCEPROP 1 LAST MATERIAL EMPTY
J 2
(-2500 -650);
DISPLAY 0.617021 (-2500 -650);
PAINT RED (-2500 -650);
FORCEPROP 1 LAST VALUE 1000PF
J 2
(-2500 -500);
DISPLAY 0.617021 (-2500 -500);
PAINT SKYBLUE (-2500 -500);
FORCEPROP 1 LAST VOLTAGE 50V
J 2
(-2500 -550);
DISPLAY 0.617021 (-2500 -550);
PAINT SKYBLUE (-2500 -550);
FORCEPROP 1 LAST PACK_TYPE 0402
J 2
(-2500 -750);
DISPLAY 0.617021 (-2500 -750);
PAINT SKYBLUE (-2500 -750);
FORCEPROP 1 LAST LOCATION PC2286
J 2
(-2500 -450);
DISPLAY 0.723404 (-2500 -450);
PAINT AQUA (-2500 -450);
FORCEPROP 1 LASTPIN (-2450 -475) $PN 1
J 2
(-2460 -495);
DISPLAY 0.617021 (-2460 -495);
FORCEPROP 1 LASTPIN (-2450 -675) $PN 2
J 2
(-2460 -695);
DISPLAY 0.617021 (-2460 -695);
FORCEPROP 2 LAST CDS_LIB pure_quanta
J 2
(-2450 -575);
PAINT MONO (-2450 -575);
DISPLAY INVISIBLE (-2450 -575);
FORCEPROP 1 LAST PATH I8
J 2
(-2500 -425);
DISPLAY 0.978723 (-2500 -425);
PAINT WHITE (-2500 -425);
DISPLAY INVISIBLE (-2500 -425);
FORCEPROP 2 LAST $SEC 1
J 0
(-2500 -375);
DISPLAY 0.680851 (-2500 -375);
PAINT MONO (-2500 -375);
DISPLAY INVISIBLE (-2500 -375);
FORCEPROP 2 LAST CDS_SEC 1
J 0
(-2500 -375);
DISPLAY 1.021277 (-2500 -375);
DISPLAY INVISIBLE (-2500 -375);
FORCEADD Q_RES..2
(-2350 -575);
FORCEPROP 1 LAST PART_NUMBER CS22002FB07
J 0
(-2310 -700);
DISPLAY 0.617021 (-2310 -700);
PAINT BLUE (-2310 -700);
DISPLAY INVISIBLE (-2310 -700);
FORCEPROP 1 LAST MATERIAL CHIP
J 0
(-2310 -650);
DISPLAY 0.617021 (-2310 -650);
PAINT SKYBLUE (-2310 -650);
FORCEPROP 1 LAST WATTAGE 1/16W
J 0
(-2310 -600);
DISPLAY 0.617021 (-2310 -600);
PAINT SKYBLUE (-2310 -600);
FORCEPROP 1 LAST VALUE 2K
J 0
(-2305 -500);
DISPLAY 0.617021 (-2305 -500);
PAINT SKYBLUE (-2305 -500);
FORCEPROP 1 LAST TOLERANCE 1%
J 0
(-2305 -550);
DISPLAY 0.617021 (-2305 -550);
PAINT SKYBLUE (-2305 -550);
FORCEPROP 1 LAST PACK_TYPE 0402LF
J 0
(-2310 -750);
DISPLAY 0.617021 (-2310 -750);
PAINT SKYBLUE (-2310 -750);
FORCEPROP 1 LAST LOCATION PR1649
J 0
(-2305 -450);
DISPLAY 0.723404 (-2305 -450);
PAINT AQUA (-2305 -450);
FORCEPROP 1 LASTPIN (-2350 -475) $PN 1
J 0
(-2345 -513);
DISPLAY 0.617021 (-2345 -513);
FORCEPROP 1 LASTPIN (-2350 -675) $PN 2
J 0
(-2345 -665);
DISPLAY 0.617021 (-2345 -665);
FORCEPROP 2 LAST CDS_LIB pure_quanta
J 0
(-2350 -575);
PAINT MONO (-2350 -575);
DISPLAY INVISIBLE (-2350 -575);
FORCEPROP 1 LAST PATH I9
J 0
(-2300 -400);
DISPLAY 0.978723 (-2300 -400);
PAINT WHITE (-2300 -400);
DISPLAY INVISIBLE (-2300 -400);
FORCEPROP 2 LAST $SEC 1
J 0
(-2300 -350);
DISPLAY 0.680851 (-2300 -350);
PAINT MONO (-2300 -350);
DISPLAY INVISIBLE (-2300 -350);
FORCEPROP 2 LAST CDS_SEC 1
J 0
(-2300 -350);
DISPLAY 1.021277 (-2300 -350);
DISPLAY INVISIBLE (-2300 -350);
FORCEADD DNS..2
(-2450 -600);
PAINT RED (-2450 -600);
FORCEPROP 1 LAST COMMENT_BODY TRUE
R 1
J 0
(-2375 -825);
DISPLAY 0.872340 (-2375 -825);
PAINT GREEN (-2375 -825);
DISPLAY INVISIBLE (-2375 -825);
FORCEPROP 2 LAST CDS_LIB mstr_misc
J 0
(-2450 -600);
PAINT MONO (-2450 -600);
DISPLAY INVISIBLE (-2450 -600);
FORCEADD DNS..2
(-2925 -75);
PAINT RED (-2925 -75);
FORCEPROP 1 LAST COMMENT_BODY TRUE
R 1
J 0
(-2850 -300);
DISPLAY 0.872340 (-2850 -300);
PAINT GREEN (-2850 -300);
DISPLAY INVISIBLE (-2850 -300);
FORCEPROP 2 LAST CDS_LIB mstr_misc
J 0
(-2925 -75);
PAINT MONO (-2925 -75);
DISPLAY INVISIBLE (-2925 -75);
FORCEADD QUANTA_TITLE_BLOCK_C..1
(4275 -3300);
FORCEPROP 0 LAST CDS_CON_LAST_MODIFIED Fri Aug 25 14:04:33 2023
J 0
(2390 -3285);
DISPLAY INVISIBLE (2390 -3285);
FORCEPROP 1 LAST CUSTOM_TXT_CDS <CON_LAST_MODIFIED>
J 0
(2390 -3285);
DISPLAY 0.978723 (2390 -3285);
FORCEPROP 2 LAST CUSTOM_TXT_CDS <XR_PAGE_TITLE>
J 0
(-3615 1950);
DISPLAY 0.638298 (-3615 1950);
PAINT PINK (-3615 1950);
DISPLAY INVISIBLE (-3615 1950);
FORCEPROP 1 LAST CUSTOM_TXT_CDS <NAME_2>
J 0
(1100 -3250);
FORCEPROP 1 LAST CUSTOM_TXT_CDS <NAME_1>
J 0
(1100 -3125);
FORCEPROP 1 LAST CUSTOM_TXT_CDS <Q_NUMBER>
J 0
(2872 -3197);
DISPLAY 1.212766 (2872 -3197);
FORCEPROP 1 LAST CUSTOM_TXT_CDS <Q_PROJ>
J 0
(1893 -3198);
DISPLAY 1.212766 (1893 -3198);
FORCEPROP 1 LAST CUSTOM_TXT_CDS <Q_REV>
J 0
(4091 -3197);
DISPLAY 1.212766 (4091 -3197);
FORCEPROP 1 LAST CUSTOM_TXT_CDS <CON_PAGE_NUM> OF <CON_TOTAL_PAGES>
J 0
(3829 -3282);
DISPLAY 0.978723 (3829 -3282);
FORCEPROP 1 LAST Q_TITLE MPQ8633B/P1V05_PCH_AUX VR
J 0
(-5025 -3225);
DISPLAY 2.446809 (-5025 -3225);
PAINT GREEN (-5025 -3225);
FORCEPROP 1 LAST Q_DEPT 
J 1
(512 -3251);
DISPLAY 1.957447 (512 -3251);
PAINT GREEN (512 -3251);
FORCEPROP 2 LAST CDS_XR_PAGE_TITLE CR-262 : @S9S_MB_2U_LIB.S9S_MB_2U(SCH_1):PAGE262
J 0
(-3615 1950);
DISPLAY 0.638298 (-3615 1950);
PAINT PINK (-3615 1950);
DISPLAY INVISIBLE (-3615 1950);
FORCEPROP 2 LAST CDS_LIB pure_quanta
J 0
(4275 -3300);
DISPLAY INVISIBLE (4275 -3300);
FORCEPROP 1 LAST CDS_LMAN_SYM_OUTLINE -9475,6775,100,-125
J 0
(4275 -3300);
DISPLAY 0.468085 (4275 -3300);
PAINT GREEN (4275 -3300);
DISPLAY INVISIBLE (4275 -3300);
FORCEPROP 2 LAST PAGE_BORDER TRUE
J 0
(-3615 1950);
DISPLAY 0.638298 (-3615 1950);
PAINT PINK (-3615 1950);
DISPLAY INVISIBLE (-3615 1950);
FORCEPROP 1 LAST COMMENT_BODY TRUE
J 0
(4287 -3313);
DISPLAY 0.978723 (4287 -3313);
PAINT GREEN (4287 -3313);
DISPLAY INVISIBLE (4287 -3313);
WIRE 16 -1 (-3150 -900)(-3150 -825);
WIRE 16 -1 (-4900 1000)(-4900 625);
WIRE 16 -1 (-3750 -50)(-3750 -75);
WIRE 16 -1 (450 625)(450 725);
WIRE 16 -1 (3675 -2250)(3675 -2300);
WIRE 16 -1 (3825 -350)(3825 -175);
WIRE 16 -1 (3450 -350)(3825 -350);
WIRE 16 -1 (3825 -350)(3825 -1050);
WIRE 16 -1 (-3150 -1525)(-3150 -1650);
WIRE 16 -1 (-2100 -1550)(-2100 -1650);
WIRE 16 -1 (-2350 -750)(-2350 -850);
WIRE 16 -1 (-2450 -750)(-2350 -750);
WIRE 16 -1 (-2350 -675)(-2350 -750);
WIRE 16 -1 (-1375 -675)(-1375 -650);
WIRE 16 -1 (-425 -1450)(-425 -1200);
WIRE 16 -1 (-275 -1375)(-275 -1475);
WIRE 16 -1 (-4900 225)(-4900 325);
WIRE 16 -1 (-4325 150)(-4325 100);
WIRE 16 -1 (-4325 150)(-3725 150);
WIRE 16 -1 (-4325 275)(-4325 150);
WIRE 16 -1 (3675 -2750)(3675 -2800);
WIRE 16 -1 (3675 -2750)(3275 -2750);
WIRE 16 -1 (3675 -2600)(3675 -2750);
WIRE 16 -1 (3450 -775)(3450 -825);
WIRE 16 -1 (3025 -775)(3450 -775);
WIRE 16 -1 (3450 -775)(3450 -650);
WIRE 16 -1 (3825 -1775)(3825 -1525);
WIRE 16 -1 (3825 -1050)(3125 -1050);
WIRE 16 -1 (3450 -450)(3450 -350);
WIRE 16 -1 (3025 -450)(3025 -350);
WIRE 16 -1 (3025 -350)(3450 -350);
WIRE 16 -1 (2650 -450)(2650 -350);
WIRE 16 -1 (2650 -350)(3025 -350);
WIRE 16 -1 (2225 -450)(2225 -350);
WIRE 16 -1 (2225 -350)(2650 -350);
WIRE 16 -1 (1475 -350)(2225 -350);
WIRE 16 2175 (1750 1575)(3628 1575);
WIRE 16 2175 (3628 2650)(3628 1575);
WIRE 16 2175 (1750 2650)(1750 1575);
WIRE 16 2175 (1750 2650)(3628 2650);
WIRE 16 -1 (1075 275)(2325 275);
FORCEPROP 2 LAST SIG_NAME PWRGD_PVNN_PCH_AUX
J 0
(1465 285);
DISPLAY 0.617021 (1465 285);
WIRE 16 -1 (2325 150)(1075 150);
FORCEPROP 2 LAST SIG_NAME PWRGD_P1V05_PCH_AUX
J 0
(1465 160);
DISPLAY 0.617021 (1465 160);
WIRE 16 -1 (675 275)(875 275);
WIRE 16 -1 (675 150)(675 275);
WIRE 16 -1 (875 150)(675 150);
WIRE 16 -1 (450 425)(450 150);
WIRE 16 -1 (675 150)(450 150);
WIRE 16 -1 (-525 150)(450 150);
FORCEPROP 2 LAST SIG_NAME PWRGD_P1V05_PCH_AUX_R
J 0
(-310 160);
DISPLAY 0.617021 (-310 160);
WIRE 16 -1 (3675 -2300)(3675 -2400);
WIRE 16 -1 (3275 -2400)(3275 -2300);
WIRE 16 -1 (3675 -2300)(3275 -2300);
WIRE 16 -1 (3275 -2300)(2875 -2300);
WIRE 16 -1 (2875 -2400)(2875 -2300);
WIRE 16 -1 (3825 -1525)(3125 -1525);
WIRE 16 -1 (3025 -650)(3025 -775);
WIRE 16 -1 (2650 -650)(2650 -775);
WIRE 16 -1 (2650 -775)(3025 -775);
WIRE 16 -1 (2225 -775)(2650 -775);
WIRE 16 -1 (2225 -650)(2225 -775);
WIRE 16 -1 (2875 -2600)(2875 -2750);
WIRE 16 -1 (3275 -2750)(2875 -2750);
WIRE 16 -1 (3275 -2600)(3275 -2750);
WIRE 16 -1 (2100 -1275)(1750 -1275);
WIRE 16 -1 (1750 -1050)(2100 -1050);
WIRE 16 -1 (2100 -1050)(2100 -1275);
WIRE 16 -1 (2100 -1050)(2325 -1050);
FORCEPROP 2 LAST SIG_NAME SH_P1V05_PCH_AUX_P
J 0
(2265 -1040);
DISPLAY 0.617021 (2265 -1040);
WIRE 16 -1 (2325 -1150)(2325 -1050);
WIRE 16 -1 (2325 -1050)(2875 -1050);
WIRE 16 -1 (2325 -1350)(2325 -1525);
WIRE 16 -1 (2325 -1525)(2875 -1525);
WIRE 16 -1 (-525 -950)(600 -950);
WIRE 16 -1 (700 -1400)(700 -1525);
WIRE 16 -1 (700 -1525)(2325 -1525);
FORCEPROP 2 LAST SIG_NAME SH_P1V05_PCH_AUX_N
J 0
(2265 -1515);
DISPLAY 0.638298 (2265 -1515);
WIRE 16 -1 (600 -1525)(700 -1525);
WIRE 16 -1 (600 -950)(600 -1525);
WIRE 16 -1 (175 -1525)(600 -1525);
WIRE 16 -1 (175 -1375)(175 -1525);
WIRE 16 -1 (700 -800)(-525 -800);
FORCEPROP 2 LAST SIG_NAME P1V05_PCH_AUX_FB
J 0
(-310 -790);
DISPLAY 0.638298 (-310 -790);
WIRE 16 -1 (700 -1200)(700 -1050);
WIRE 16 -1 (700 -1050)(700 -800);
WIRE 16 -1 (700 -1050)(1225 -1050);
WIRE 16 -1 (1225 -1050)(1550 -1050);
WIRE 16 -1 (1225 -1050)(1225 -1275);
WIRE 16 -1 (1225 -1275)(1550 -1275);
WIRE 16 -1 (-450 -50)(-525 -50);
WIRE 16 -1 (-450 50)(-450 -50);
WIRE 16 -1 (-450 50)(350 50);
FORCEPROP 2 LAST SIG_NAME SW_P1V05_PCH_AUX_BST
J 0
(-310 60);
DISPLAY 0.617021 (-310 60);
WIRE 16 -1 (350 -25)(350 50);
WIRE 16 -1 (350 -225)(350 -350);
WIRE 16 -1 (350 -350)(1275 -350);
WIRE 16 -1 (-525 -350)(350 -350);
FORCEPROP 2 LAST SIG_NAME SW_P1V05_PCH_AUX_SW
J 0
(-310 -340);
DISPLAY 0.617021 (-310 -340);
WIRE 16 -1 (-1500 100)(-1325 100);
WIRE 16 -1 (-1500 150)(-1500 100);
WIRE 16 -1 (-1325 150)(-1500 150);
WIRE 16 -1 (-1500 150)(-1500 625);
WIRE 16 -1 (-2425 625)(-2425 475);
WIRE 16 -1 (-1500 625)(-2425 625);
WIRE 16 -1 (-2850 475)(-2850 625);
WIRE 16 -1 (-2425 625)(-2850 625);
WIRE 16 -1 (-3275 475)(-3275 625);
WIRE 16 -1 (-2850 625)(-3275 625);
WIRE 16 -1 (-3725 475)(-3725 625);
WIRE 16 -1 (-3275 625)(-3725 625);
WIRE 16 -1 (-4475 625)(-4325 625);
WIRE 16 -1 (-4325 625)(-3725 625);
FORCEPROP 2 LAST SIG_NAME SW_P12V_AUX_P1V05_PCH_AUX_FLT
J 0
(-2335 635);
DISPLAY 0.617021 (-2335 635);
WIRE 16 -1 (-4325 475)(-4325 625);
WIRE 16 -1 (-2250 -75)(-2850 -75);
WIRE 16 -1 (-2250 -350)(-2250 -75);
WIRE 16 -1 (-2250 -350)(-1325 -350);
FORCEPROP 2 LAST SIG_NAME FM_P1V05_PCH_AUX_R_EN
J 0
(-2035 -340);
DISPLAY 0.617021 (-2035 -340);
WIRE 16 -1 (-2850 -350)(-2350 -350);
WIRE 16 -1 (-2250 -350)(-2350 -350);
FORCEPROP 0 LAST CDS_PHYS_NET_NAME FM_P1V05_PCH_AUX_R_EN
J 0
(-2285 -310);
PAINT MONO (-2285 -310);
DISPLAY INVISIBLE (-2285 -310);
WIRE 16 -1 (-2350 -425)(-2350 -350);
WIRE 16 -1 (-2350 -475)(-2350 -425);
WIRE 16 -1 (-2450 -425)(-2350 -425);
WIRE 16 -1 (-2450 -475)(-2450 -425);
WIRE 16 -1 (-3725 275)(-3725 150);
WIRE 16 -1 (-3275 150)(-3725 150);
WIRE 16 -1 (-3275 275)(-3275 150);
WIRE 16 -1 (-2850 150)(-3275 150);
WIRE 16 -1 (-2850 275)(-2850 150);
WIRE 16 -1 (-2425 150)(-2850 150);
WIRE 16 -1 (-2425 275)(-2425 150);
WIRE 16 -1 (-4050 -350)(-3050 -350);
FORCEPROP 0 LAST CDS_PHYS_NET_NAME FM_P1V05_PCH_AUX_EN
J 0
(-4010 -310);
PAINT MONO (-4010 -310);
DISPLAY INVISIBLE (-4010 -310);
FORCEPROP 2 LAST SIG_NAME FM_P1V05_PCH_AUX_EN
J 0
(-3960 -340);
DISPLAY 0.617021 (-3960 -340);
WIRE 16 -1 (-3750 -75)(-3050 -75);
WIRE 16 -1 (-4675 625)(-4900 625);
WIRE 16 -1 (-4900 525)(-4900 625);
WIRE 16 -1 (-1325 -550)(-2025 -550);
FORCEPROP 2 LAST SIG_NAME P1V05_PCH_AUX_MODE
J 0
(-2035 -540);
DISPLAY 0.638298 (-2035 -540);
WIRE 16 -1 (-2025 -650)(-2025 -550);
WIRE 16 -1 (-1725 -650)(-2025 -650);
WIRE 16 -1 (175 -1050)(175 -1175);
WIRE 16 -1 (-275 -1175)(-275 -1050);
WIRE 16 -1 (-275 -1050)(175 -1050);
WIRE 16 -1 (-525 -1050)(-275 -1050);
FORCEPROP 2 LAST SIG_NAME P1V05_PCH_AUX_REF
J 0
(-310 -1040);
DISPLAY 0.617021 (-310 -1040);
WIRE 16 -1 (-525 -1150)(-425 -1150);
WIRE 16 -1 (-425 -1150)(-425 -1200);
WIRE 16 -1 (-525 -1200)(-425 -1200);
WIRE 16 -1 (-1375 -650)(-1525 -650);
WIRE 16 -1 (-2450 -675)(-2450 -750);
WIRE 16 -1 (-3150 -1250)(-3150 -1325);
WIRE 16 -1 (-3150 -1100)(-3150 -1250);
WIRE 16 -1 (-2175 -1250)(-3150 -1250);
WIRE 16 -1 (-2175 -800)(-2175 -1250);
WIRE 16 -1 (-2175 -800)(-1325 -800);
FORCEPROP 2 LAST SIG_NAME P1V05_PCH_AUX_VCC
J 0
(-2035 -790);
DISPLAY 0.617021 (-2035 -790);
WIRE 16 -1 (-2100 -1150)(-2100 -1350);
WIRE 16 -1 (-1325 -1150)(-2100 -1150);
FORCEPROP 2 LAST SIG_NAME P1V05_PCH_AUX_CS
J 0
(-2035 -1140);
DISPLAY 0.617021 (-2035 -1140);
WIRE 16 2175 (-4300 -2750)(-3450 -2750);
WIRE 16 2175 (-3450 -2300)(-3450 -2750);
WIRE 16 2175 (-4300 -2300)(-4300 -2750);
WIRE 16 2175 (-4300 -2300)(-3450 -2300);
DOT 1 (3825 -350);
DOT 1 (3450 -350);
DOT 1 (3025 -350);
DOT 1 (2650 -350);
DOT 1 (2225 -350);
DOT 1 (675 150);
DOT 1 (3675 -2300);
DOT 1 (3450 -775);
DOT 1 (3025 -775);
DOT 1 (2650 -775);
DOT 1 (3275 -2300);
DOT 1 (3675 -2750);
DOT 1 (3275 -2750);
DOT 1 (2100 -1050);
DOT 1 (2325 -1050);
CIRCLE (2975 -1275)(3391 -1275);
PAINT YELLOW (2975 -1275);
DOT 1 (2325 -1525);
DOT 1 (1225 -1050);
DOT 1 (700 -1050);
DOT 1 (700 -1525);
DOT 1 (600 -1525);
DOT 1 (450 150);
DOT 1 (350 -350);
DOT 1 (-2425 625);
DOT 1 (-1500 150);
DOT 1 (-2250 -350);
DOT 1 (-2350 -425);
DOT 1 (-2350 -350);
DOT 1 (-2850 625);
DOT 1 (-3275 625);
DOT 1 (-2850 150);
DOT 1 (-3275 150);
DOT 1 (-3725 625);
DOT 1 (-4325 625);
DOT 1 (-3725 150);
DOT 1 (-4325 150);
DOT 1 (-4900 625);
DOT 1 (-275 -1050);
DOT 1 (-425 -1200);
DOT 1 (-2350 -750);
DOT 1 (-3150 -1250);
FORCENOTE
SLEW RATE=74A/US
(1776 1811) 0;
DISPLAY LEFT (1776 1811);
DISPLAY 1.170213 (1776 1811);
PAINT WHITE (1776 1811);
FORCENOTE
CURRENT STEP=6.8A
(1776 1886) 0;
DISPLAY LEFT (1776 1886);
DISPLAY 1.170213 (1776 1886);
PAINT WHITE (1776 1886);
FORCENOTE
OCP(IMAX*130%)=15.6A
(1776 1961) 0;
DISPLAY LEFT (1776 1961);
DISPLAY 1.170213 (1776 1961);
PAINT WHITE (1776 1961);
FORCENOTE
MAX CURRENT=12A
(1776 2036) 0;
DISPLAY LEFT (1776 2036);
DISPLAY 1.170213 (1776 2036);
PAINT WHITE (1776 2036);
FORCENOTE
TOTAL TOL=+3%~-5% 
(1778 2186) 0;
DISPLAY LEFT (1778 2186);
DISPLAY 1.276596 (1778 2186);
PAINT WHITE (1778 2186);
FORCENOTE
DC TOLERANCE=+/-1%
(1787 2344) 0;
DISPLAY LEFT (1787 2344);
DISPLAY 1.276596 (1787 2344);
PAINT WHITE (1787 2344);
FORCENOTE
P1V05_PCH_AUX SPECIFICATION
(1775 2565) 0;
DISPLAY LEFT (1775 2565);
DISPLAY 1.468085 (1775 2565);
PAINT WHITE (1775 2565);
FORCENOTE
WORK FREQUENCY=600KHZ
(1776 1741) 0;
DISPLAY LEFT (1776 1741);
DISPLAY 1.170213 (1776 1741);
PAINT WHITE (1776 1741);
FORCENOTE
20220808 UPDATE PDG REV 1.6
(1775 1425) 0;
DISPLAY LEFT (1775 1425);
DISPLAY 1.595745 (1775 1425);
FORCENOTE
TDC=10.9A
(1776 2111) 0;
DISPLAY LEFT (1776 2111);
DISPLAY 1.170213 (1776 2111);
PAINT WHITE (1776 2111);
FORCENOTE
RIPPLE=+/-0.5%
(1775 2265) 0;
DISPLAY LEFT (1775 2265);
DISPLAY 1.170213 (1775 2265);
PAINT WHITE (1775 2265);
FORCENOTE
VOUT=1.05V
(1775 2415) 0;
DISPLAY LEFT (1775 2415);
DISPLAY 1.170213 (1775 2415);
PAINT WHITE (1775 2415);
FORCENOTE
PDG REV 1.6
(1775 1625) 0;
DISPLAY LEFT (1775 1625);
DISPLAY 1.170213 (1775 1625);
PAINT RED (1775 1625);
FORCENOTE
ISAT=29A@125C
(1150 -550) 0;
DISPLAY LEFT (1150 -550);
DISPLAY 0.808511 (1150 -550);
FORCENOTE
PG1712.301AHLT
(1150 -450) 0;
DISPLAY LEFT (1150 -450);
DISPLAY 0.808511 (1150 -450);
FORCENOTE
9.6*6.4*9.0
(1150 -500) 0;
DISPLAY LEFT (1150 -500);
DISPLAY 0.808511 (1150 -500);
FORCENOTE
DCR=0.17MOHM
(1150 -600) 0;
DISPLAY LEFT (1150 -600);
DISPLAY 0.808511 (1150 -600);
FORCENOTE
REMOTE SENSE
(3200 -1300) 0;
DISPLAY LEFT (3200 -1300);
DISPLAY 1.021277 (3200 -1300);
FORCENOTE
PLACE AT CHIPSET SIDE
(3200 -1375) 0;
DISPLAY LEFT (3200 -1375);
DISPLAY 1.021277 (3200 -1375);
FORCENOTE
RA
(1600 -975) 0;
DISPLAY LEFT (1600 -975);
DISPLAY 1.021277 (1600 -975);
FORCENOTE
3RD 680PF
(1850 -2225) 0;
DISPLAY LEFT (1850 -2225);
DISPLAY 1.276596 (1850 -2225);
PAINT PINK (1850 -2225);
FORCENOTE
2ND 1000PF
(1850 -2125) 0;
DISPLAY LEFT (1850 -2125);
DISPLAY 1.276596 (1850 -2125);
PAINT PINK (1850 -2125);
FORCENOTE
VOUT=((RA/RB)+1)*0.6
(650 -1700) 0;
DISPLAY LEFT (650 -1700);
DISPLAY 1.021277 (650 -1700);
PAINT SKYBLUE (650 -1700);
FORCENOTE
((7.32/10)+1)*0.6=1.0392
(650 -1775) 0;
DISPLAY LEFT (650 -1775);
DISPLAY 1.021277 (650 -1775);
PAINT SKYBLUE (650 -1775);
FORCENOTE
PC1223 MAIN 680PF
(1375 -2025) 0;
DISPLAY LEFT (1375 -2025);
DISPLAY 1.276596 (1375 -2025);
PAINT PINK (1375 -2025);
FORCENOTE
20220808 ADD CHANGE LIST
(675 -1925) 0;
DISPLAY LEFT (675 -1925);
DISPLAY 1.595745 (675 -1925);
PAINT PINK (675 -1925);
FORCENOTE
RB
(725 -1125) 0;
DISPLAY LEFT (725 -1125);
DISPLAY 1.021277 (725 -1125);
FORCENOTE
P1V05_PCH_AUX
(-1900 1525) 0;
DISPLAY LEFT (-1900 1525);
DISPLAY 3.936170 (-1900 1525);
PAINT YELLOW (-1900 1525);
FORCENOTE
PC113 MAIN 1UF
(-3325 -1975) 0;
DISPLAY LEFT (-3325 -1975);
DISPLAY 1.276596 (-3325 -1975);
PAINT PINK (-3325 -1975);
FORCENOTE
2ND 2.2UF
(-2900 -2075) 0;
DISPLAY LEFT (-2900 -2075);
DISPLAY 1.276596 (-2900 -2075);
PAINT PINK (-2900 -2075);
FORCENOTE
3RD 1UF
(-2900 -2175) 0;
DISPLAY LEFT (-2900 -2175);
DISPLAY 1.276596 (-2900 -2175);
PAINT PINK (-2900 -2175);
FORCENOTE
20220808 ADD CHANGE LIST
(-4075 -1875) 0;
DISPLAY LEFT (-4075 -1875);
DISPLAY 1.595745 (-4075 -1875);
PAINT PINK (-4075 -1875);
FORCENOTE
20220804 CHANGE IC TABLE
(-4275 -2850) 0;
DISPLAY LEFT (-4275 -2850);
DISPLAY 1.595745 (-4275 -2850);
PAINT PINK (-4275 -2850);
FORCENOTE
3RD AL008633005
(-4250 -2650) 0;
DISPLAY LEFT (-4250 -2650);
DISPLAY 1.021277 (-4250 -2650);
PAINT WHITE (-4250 -2650);
FORCENOTE
1ST AL053319002
(-4250 -2500) 0;
DISPLAY LEFT (-4250 -2500);
DISPLAY 1.021277 (-4250 -2500);
PAINT WHITE (-4250 -2500);
FORCENOTE
2ND AL000548007
(-4250 -2575) 0;
DISPLAY LEFT (-4250 -2575);
DISPLAY 1.021277 (-4250 -2575);
PAINT WHITE (-4250 -2575);
FORCENOTE
IC TABLE
(-4275 -2400) 0;
DISPLAY LEFT (-4275 -2400);
DISPLAY 1.170213 (-4275 -2400);
PAINT WHITE (-4275 -2400);
QUIT
